FILE_TYPE = MACRO_DRAWING;
SET COLOR_WIRE YELLOW;
SET COLOR_PROP MONO;
SET COLOR_DOT WHITE;
SET COLOR_ARC YELLOW;
SET COLOR_BODY GREEN;
SET COLOR_NOTE MONO;
SET PROP_DISPLAY VALUE;
SET PAGE_NUMBER P45;
FORCEADD OFFPAGE..3
(1600 5200);
FORCEPROP 2 LAST $XR1 46 
J 0
(1904 5200);
DISPLAY 0.638298 (1904 5200);
PAINT MONO (1904 5200);
FORCEPROP 2 LAST $XR0 24 
J 0
(1814 5200);
DISPLAY 0.638298 (1814 5200);
PAINT MONO (1814 5200);
FORCEPROP 2 LAST CDS_LIB mstr_standard
J 0
(1600 5200);
DISPLAY 0.787234 (1600 5200);
PAINT MONO (1600 5200);
DISPLAY INVISIBLE (1600 5200);
FORCEPROP 1 LAST OFFPAGE TRUE
J 0
(1925 5075);
DISPLAY 0.936170 (1925 5075);
PAINT GREEN (1925 5075);
DISPLAY INVISIBLE (1925 5075);
FORCEPROP 1 LAST COMMENT_BODY TRUE
J 0
(1550 5100);
DISPLAY 0.936170 (1550 5100);
PAINT GREEN (1550 5100);
DISPLAY INVISIBLE (1550 5100);
FORCEPROP 2 LAST PATH I1
J 0
(1800 5275);
DISPLAY 0.787234 (1800 5275);
PAINT MONO (1800 5275);
DISPLAY INVISIBLE (1800 5275);
FORCEADD TAP..6
R 2
(700 4850);
FORCEPROP 3 LASTPIN (650 4850) SIG_NAME M_B_DQS_DP<14>
J 0
(660 4860);
DISPLAY 0.659574 (660 4860);
PAINT MONO (660 4860);
DISPLAY INVISIBLE (660 4860);
FORCEPROP 1 LASTPIN (650 4850) BN 14
J 2
(700 4860);
DISPLAY 0.617021 (700 4860);
PAINT PINK (700 4860);
FORCEPROP 2 LAST CDS_LIB mstr_standard
J 0
(700 4850);
DISPLAY 0.787234 (700 4850);
PAINT MONO (700 4850);
DISPLAY INVISIBLE (700 4850);
FORCEPROP 1 LAST BODY_TYPE PLUMBING
J 2
(700 4800);
DISPLAY 1.234043 (700 4800);
PAINT GREEN (700 4800);
DISPLAY INVISIBLE (700 4800);
FORCEPROP 1 LAST HDL_TAP TRUE
J 2
(375 4725);
DISPLAY 1.234043 (375 4725);
PAINT GREEN (375 4725);
DISPLAY INVISIBLE (375 4725);
FORCEPROP 1 LAST PATH I10
J 2
(700 4850);
DISPLAY 0.936170 (700 4850);
PAINT GREEN (700 4850);
DISPLAY INVISIBLE (700 4850);
FORCEADD TAP..6
R 2
(-1700 1850);
FORCEPROP 3 LASTPIN (-1750 1850) SIG_NAME M_B_DQ<9>
J 0
(-1740 1860);
DISPLAY 0.659574 (-1740 1860);
PAINT MONO (-1740 1860);
DISPLAY INVISIBLE (-1740 1860);
FORCEPROP 1 LASTPIN (-1750 1850) BN 9
J 2
(-1700 1860);
DISPLAY 0.617021 (-1700 1860);
PAINT PINK (-1700 1860);
FORCEPROP 2 LAST CDS_LIB mstr_standard
J 2
(-1700 1850);
DISPLAY 0.787234 (-1700 1850);
PAINT MONO (-1700 1850);
DISPLAY INVISIBLE (-1700 1850);
FORCEPROP 1 LAST BODY_TYPE PLUMBING
J 2
(-1700 1800);
DISPLAY 1.234043 (-1700 1800);
PAINT GREEN (-1700 1800);
DISPLAY INVISIBLE (-1700 1800);
FORCEPROP 1 LAST HDL_TAP TRUE
J 2
(-2025 1725);
DISPLAY 1.234043 (-2025 1725);
PAINT GREEN (-2025 1725);
DISPLAY INVISIBLE (-2025 1725);
FORCEPROP 1 LAST PATH I100
J 2
(-1700 1850);
DISPLAY 0.936170 (-1700 1850);
PAINT GREEN (-1700 1850);
DISPLAY INVISIBLE (-1700 1850);
FORCEADD TAP..6
R 2
(-1700 1950);
FORCEPROP 3 LASTPIN (-1750 1950) SIG_NAME M_B_DQ<11>
J 0
(-1740 1960);
DISPLAY 0.659574 (-1740 1960);
PAINT MONO (-1740 1960);
DISPLAY INVISIBLE (-1740 1960);
FORCEPROP 1 LASTPIN (-1750 1950) BN 11
J 2
(-1700 1960);
DISPLAY 0.617021 (-1700 1960);
PAINT PINK (-1700 1960);
FORCEPROP 2 LAST CDS_LIB mstr_standard
J 2
(-1700 1950);
DISPLAY 0.787234 (-1700 1950);
PAINT MONO (-1700 1950);
DISPLAY INVISIBLE (-1700 1950);
FORCEPROP 1 LAST BODY_TYPE PLUMBING
J 2
(-1700 1900);
DISPLAY 1.234043 (-1700 1900);
PAINT GREEN (-1700 1900);
DISPLAY INVISIBLE (-1700 1900);
FORCEPROP 1 LAST HDL_TAP TRUE
J 2
(-2025 1825);
DISPLAY 1.234043 (-2025 1825);
PAINT GREEN (-2025 1825);
DISPLAY INVISIBLE (-2025 1825);
FORCEPROP 1 LAST PATH I101
J 2
(-1700 1950);
DISPLAY 0.936170 (-1700 1950);
PAINT GREEN (-1700 1950);
DISPLAY INVISIBLE (-1700 1950);
FORCEADD TAP..6
R 2
(-1700 1900);
FORCEPROP 3 LASTPIN (-1750 1900) SIG_NAME M_B_DQ<8>
J 0
(-1740 1910);
DISPLAY 0.659574 (-1740 1910);
PAINT MONO (-1740 1910);
DISPLAY INVISIBLE (-1740 1910);
FORCEPROP 1 LASTPIN (-1750 1900) BN 8
J 2
(-1700 1910);
DISPLAY 0.617021 (-1700 1910);
PAINT PINK (-1700 1910);
FORCEPROP 2 LAST CDS_LIB mstr_standard
J 2
(-1700 1900);
DISPLAY 0.787234 (-1700 1900);
PAINT MONO (-1700 1900);
DISPLAY INVISIBLE (-1700 1900);
FORCEPROP 1 LAST BODY_TYPE PLUMBING
J 2
(-1700 1850);
DISPLAY 1.234043 (-1700 1850);
PAINT GREEN (-1700 1850);
DISPLAY INVISIBLE (-1700 1850);
FORCEPROP 1 LAST HDL_TAP TRUE
J 2
(-2025 1775);
DISPLAY 1.234043 (-2025 1775);
PAINT GREEN (-2025 1775);
DISPLAY INVISIBLE (-2025 1775);
FORCEPROP 1 LAST PATH I102
J 2
(-1700 1900);
DISPLAY 0.936170 (-1700 1900);
PAINT GREEN (-1700 1900);
DISPLAY INVISIBLE (-1700 1900);
FORCEADD TAP..6
R 2
(-1700 1700);
FORCEPROP 3 LASTPIN (-1750 1700) SIG_NAME M_B_DQ<4>
J 0
(-1740 1710);
DISPLAY 0.659574 (-1740 1710);
PAINT MONO (-1740 1710);
DISPLAY INVISIBLE (-1740 1710);
FORCEPROP 1 LASTPIN (-1750 1700) BN 4
J 2
(-1700 1710);
DISPLAY 0.617021 (-1700 1710);
PAINT PINK (-1700 1710);
FORCEPROP 2 LAST CDS_LIB mstr_standard
J 2
(-1700 1700);
DISPLAY 0.787234 (-1700 1700);
PAINT MONO (-1700 1700);
DISPLAY INVISIBLE (-1700 1700);
FORCEPROP 1 LAST BODY_TYPE PLUMBING
J 2
(-1700 1650);
DISPLAY 1.234043 (-1700 1650);
PAINT GREEN (-1700 1650);
DISPLAY INVISIBLE (-1700 1650);
FORCEPROP 1 LAST HDL_TAP TRUE
J 2
(-2025 1575);
DISPLAY 1.234043 (-2025 1575);
PAINT GREEN (-2025 1575);
DISPLAY INVISIBLE (-2025 1575);
FORCEPROP 1 LAST PATH I103
J 2
(-1700 1700);
DISPLAY 0.936170 (-1700 1700);
PAINT GREEN (-1700 1700);
DISPLAY INVISIBLE (-1700 1700);
FORCEADD TAP..6
R 2
(-1700 1750);
FORCEPROP 3 LASTPIN (-1750 1750) SIG_NAME M_B_DQ<7>
J 0
(-1740 1760);
DISPLAY 0.659574 (-1740 1760);
PAINT MONO (-1740 1760);
DISPLAY INVISIBLE (-1740 1760);
FORCEPROP 1 LASTPIN (-1750 1750) BN 7
J 2
(-1700 1760);
DISPLAY 0.617021 (-1700 1760);
PAINT PINK (-1700 1760);
FORCEPROP 2 LAST CDS_LIB mstr_standard
J 2
(-1700 1750);
DISPLAY 0.787234 (-1700 1750);
PAINT MONO (-1700 1750);
DISPLAY INVISIBLE (-1700 1750);
FORCEPROP 1 LAST BODY_TYPE PLUMBING
J 2
(-1700 1700);
DISPLAY 1.234043 (-1700 1700);
PAINT GREEN (-1700 1700);
DISPLAY INVISIBLE (-1700 1700);
FORCEPROP 1 LAST HDL_TAP TRUE
J 2
(-2025 1625);
DISPLAY 1.234043 (-2025 1625);
PAINT GREEN (-2025 1625);
DISPLAY INVISIBLE (-2025 1625);
FORCEPROP 1 LAST PATH I104
J 2
(-1700 1750);
DISPLAY 0.936170 (-1700 1750);
PAINT GREEN (-1700 1750);
DISPLAY INVISIBLE (-1700 1750);
FORCEADD TAP..6
R 2
(-1700 1800);
FORCEPROP 3 LASTPIN (-1750 1800) SIG_NAME M_B_DQ<6>
J 0
(-1740 1810);
DISPLAY 0.659574 (-1740 1810);
PAINT MONO (-1740 1810);
DISPLAY INVISIBLE (-1740 1810);
FORCEPROP 1 LASTPIN (-1750 1800) BN 6
J 2
(-1700 1810);
DISPLAY 0.617021 (-1700 1810);
PAINT PINK (-1700 1810);
FORCEPROP 2 LAST CDS_LIB mstr_standard
J 2
(-1700 1800);
DISPLAY 0.787234 (-1700 1800);
PAINT MONO (-1700 1800);
DISPLAY INVISIBLE (-1700 1800);
FORCEPROP 1 LAST BODY_TYPE PLUMBING
J 2
(-1700 1750);
DISPLAY 1.234043 (-1700 1750);
PAINT GREEN (-1700 1750);
DISPLAY INVISIBLE (-1700 1750);
FORCEPROP 1 LAST HDL_TAP TRUE
J 2
(-2025 1675);
DISPLAY 1.234043 (-2025 1675);
PAINT GREEN (-2025 1675);
DISPLAY INVISIBLE (-2025 1675);
FORCEPROP 1 LAST PATH I105
J 2
(-1700 1800);
DISPLAY 0.936170 (-1700 1800);
PAINT GREEN (-1700 1800);
DISPLAY INVISIBLE (-1700 1800);
FORCEADD TAP..6
R 2
(-1700 1650);
FORCEPROP 3 LASTPIN (-1750 1650) SIG_NAME M_B_DQ<5>
J 0
(-1740 1660);
DISPLAY 0.659574 (-1740 1660);
PAINT MONO (-1740 1660);
DISPLAY INVISIBLE (-1740 1660);
FORCEPROP 1 LASTPIN (-1750 1650) BN 5
J 2
(-1700 1660);
DISPLAY 0.617021 (-1700 1660);
PAINT PINK (-1700 1660);
FORCEPROP 2 LAST CDS_LIB mstr_standard
J 2
(-1700 1650);
DISPLAY 0.787234 (-1700 1650);
PAINT MONO (-1700 1650);
DISPLAY INVISIBLE (-1700 1650);
FORCEPROP 1 LAST BODY_TYPE PLUMBING
J 2
(-1700 1600);
DISPLAY 1.234043 (-1700 1600);
PAINT GREEN (-1700 1600);
DISPLAY INVISIBLE (-1700 1600);
FORCEPROP 1 LAST HDL_TAP TRUE
J 2
(-2025 1525);
DISPLAY 1.234043 (-2025 1525);
PAINT GREEN (-2025 1525);
DISPLAY INVISIBLE (-2025 1525);
FORCEPROP 1 LAST PATH I106
J 2
(-1700 1650);
DISPLAY 0.936170 (-1700 1650);
PAINT GREEN (-1700 1650);
DISPLAY INVISIBLE (-1700 1650);
FORCEADD TAP..6
R 2
(-1700 1600);
FORCEPROP 3 LASTPIN (-1750 1600) SIG_NAME M_B_DQ<2>
J 0
(-1740 1610);
DISPLAY 0.659574 (-1740 1610);
PAINT MONO (-1740 1610);
DISPLAY INVISIBLE (-1740 1610);
FORCEPROP 1 LASTPIN (-1750 1600) BN 2
J 2
(-1700 1610);
DISPLAY 0.617021 (-1700 1610);
PAINT PINK (-1700 1610);
FORCEPROP 2 LAST CDS_LIB mstr_standard
J 2
(-1700 1600);
DISPLAY 0.787234 (-1700 1600);
PAINT MONO (-1700 1600);
DISPLAY INVISIBLE (-1700 1600);
FORCEPROP 1 LAST BODY_TYPE PLUMBING
J 2
(-1700 1550);
DISPLAY 1.234043 (-1700 1550);
PAINT GREEN (-1700 1550);
DISPLAY INVISIBLE (-1700 1550);
FORCEPROP 1 LAST HDL_TAP TRUE
J 2
(-2025 1475);
DISPLAY 1.234043 (-2025 1475);
PAINT GREEN (-2025 1475);
DISPLAY INVISIBLE (-2025 1475);
FORCEPROP 1 LAST PATH I107
J 2
(-1700 1600);
DISPLAY 0.936170 (-1700 1600);
PAINT GREEN (-1700 1600);
DISPLAY INVISIBLE (-1700 1600);
FORCEADD TAP..6
R 2
(-1700 1500);
FORCEPROP 3 LASTPIN (-1750 1500) SIG_NAME M_B_DQ<0>
J 0
(-1740 1510);
DISPLAY 0.659574 (-1740 1510);
PAINT MONO (-1740 1510);
DISPLAY INVISIBLE (-1740 1510);
FORCEPROP 1 LASTPIN (-1750 1500) BN 0
J 2
(-1700 1510);
DISPLAY 0.617021 (-1700 1510);
PAINT PINK (-1700 1510);
FORCEPROP 2 LAST CDS_LIB mstr_standard
J 2
(-1700 1500);
DISPLAY 0.787234 (-1700 1500);
PAINT MONO (-1700 1500);
DISPLAY INVISIBLE (-1700 1500);
FORCEPROP 1 LAST BODY_TYPE PLUMBING
J 2
(-1700 1450);
DISPLAY 1.234043 (-1700 1450);
PAINT GREEN (-1700 1450);
DISPLAY INVISIBLE (-1700 1450);
FORCEPROP 1 LAST HDL_TAP TRUE
J 2
(-2025 1375);
DISPLAY 1.234043 (-2025 1375);
PAINT GREEN (-2025 1375);
DISPLAY INVISIBLE (-2025 1375);
FORCEPROP 1 LAST PATH I108
J 2
(-1700 1500);
DISPLAY 0.936170 (-1700 1500);
PAINT GREEN (-1700 1500);
DISPLAY INVISIBLE (-1700 1500);
FORCEADD TAP..6
R 2
(-1700 1550);
FORCEPROP 3 LASTPIN (-1750 1550) SIG_NAME M_B_DQ<3>
J 0
(-1740 1560);
DISPLAY 0.659574 (-1740 1560);
PAINT MONO (-1740 1560);
DISPLAY INVISIBLE (-1740 1560);
FORCEPROP 1 LASTPIN (-1750 1550) BN 3
J 2
(-1700 1560);
DISPLAY 0.617021 (-1700 1560);
PAINT PINK (-1700 1560);
FORCEPROP 2 LAST CDS_LIB mstr_standard
J 2
(-1700 1550);
DISPLAY 0.787234 (-1700 1550);
PAINT MONO (-1700 1550);
DISPLAY INVISIBLE (-1700 1550);
FORCEPROP 1 LAST BODY_TYPE PLUMBING
J 2
(-1700 1500);
DISPLAY 1.234043 (-1700 1500);
PAINT GREEN (-1700 1500);
DISPLAY INVISIBLE (-1700 1500);
FORCEPROP 1 LAST HDL_TAP TRUE
J 2
(-2025 1425);
DISPLAY 1.234043 (-2025 1425);
PAINT GREEN (-2025 1425);
DISPLAY INVISIBLE (-2025 1425);
FORCEPROP 1 LAST PATH I109
J 2
(-1700 1550);
DISPLAY 0.936170 (-1700 1550);
PAINT GREEN (-1700 1550);
DISPLAY INVISIBLE (-1700 1550);
FORCEADD TAP..6
R 2
(-1700 1450);
FORCEPROP 3 LASTPIN (-1750 1450) SIG_NAME M_B_DQ<1>
J 0
(-1740 1460);
DISPLAY 0.659574 (-1740 1460);
PAINT MONO (-1740 1460);
DISPLAY INVISIBLE (-1740 1460);
FORCEPROP 1 LASTPIN (-1750 1450) BN 1
J 2
(-1700 1460);
DISPLAY 0.617021 (-1700 1460);
PAINT PINK (-1700 1460);
FORCEPROP 2 LAST CDS_LIB mstr_standard
J 2
(-1700 1450);
DISPLAY 0.787234 (-1700 1450);
PAINT MONO (-1700 1450);
DISPLAY INVISIBLE (-1700 1450);
FORCEPROP 1 LAST BODY_TYPE PLUMBING
J 2
(-1700 1400);
DISPLAY 1.234043 (-1700 1400);
PAINT GREEN (-1700 1400);
DISPLAY INVISIBLE (-1700 1400);
FORCEPROP 1 LAST HDL_TAP TRUE
J 2
(-2025 1325);
DISPLAY 1.234043 (-2025 1325);
PAINT GREEN (-2025 1325);
DISPLAY INVISIBLE (-2025 1325);
FORCEPROP 1 LAST PATH I110
J 2
(-1700 1450);
DISPLAY 0.936170 (-1700 1450);
PAINT GREEN (-1700 1450);
DISPLAY INVISIBLE (-1700 1450);
FORCEADD SCONN288_H44441004..1
(-2450 2950);
FORCEPROP 1 LAST MATERIAL SCONN
J 0
(-2900 4800);
DISPLAY 0.617021 (-2900 4800);
PAINT SKYBLUE (-2900 4800);
FORCEPROP 2 LASTPIN (-2950 1450) $PN 146
J 2
(-2960 1460);
DISPLAY 0.617021 (-2960 1460);
PAINT ORANGE (-2960 1460);
FORCEPROP 2 LASTPIN (-2950 1800) $PN 284
J 2
(-2960 1810);
DISPLAY 0.617021 (-2960 1810);
PAINT ORANGE (-2960 1810);
FORCEPROP 2 LASTPIN (-2950 1600) $PN 285
J 2
(-2960 1610);
DISPLAY 0.617021 (-2960 1610);
PAINT ORANGE (-2960 1610);
FORCEPROP 2 LASTPIN (-2950 1550) $PN 141
J 2
(-2960 1560);
DISPLAY 0.617021 (-2960 1560);
PAINT ORANGE (-2960 1560);
FORCEPROP 2 LASTPIN (-2950 1150) $PN 230
J 2
(-2960 1160);
DISPLAY 0.617021 (-2960 1160);
PAINT ORANGE (-2960 1160);
FORCEPROP 2 LASTPIN (-2950 1750) $PN 238
J 2
(-2960 1760);
DISPLAY 0.617021 (-2960 1760);
PAINT ORANGE (-2960 1760);
FORCEPROP 2 LASTPIN (-2950 1700) $PN 140
J 2
(-2960 1710);
DISPLAY 0.617021 (-2960 1710);
PAINT ORANGE (-2960 1710);
FORCEPROP 2 LASTPIN (-2950 1650) $PN 139
J 2
(-2960 1660);
DISPLAY 0.617021 (-2960 1660);
PAINT ORANGE (-2960 1660);
FORCEPROP 2 LASTPIN (-2950 3100) $PN 237
J 2
(-2960 3110);
DISPLAY 0.617021 (-2960 3110);
PAINT ORANGE (-2960 3110);
FORCEPROP 2 LASTPIN (-2950 3050) $PN 93
J 2
(-2960 3060);
DISPLAY 0.617021 (-2960 3060);
PAINT ORANGE (-2960 3060);
FORCEPROP 2 LASTPIN (-2950 3000) $PN 89
J 2
(-2960 3010);
DISPLAY 0.617021 (-2960 3010);
PAINT ORANGE (-2960 3010);
FORCEPROP 2 LASTPIN (-2950 2950) $PN 84
J 2
(-2960 2960);
DISPLAY 0.617021 (-2960 2960);
PAINT ORANGE (-2960 2960);
FORCEPROP 2 LASTPIN (-2950 1350) $PN 144
J 2
(-2960 1360);
DISPLAY 0.617021 (-2960 1360);
PAINT ORANGE (-2960 1360);
FORCEPROP 2 LASTPIN (-2950 1300) $PN 227
J 2
(-2960 1310);
DISPLAY 0.617021 (-2960 1310);
PAINT ORANGE (-2960 1310);
FORCEPROP 2 LASTPIN (-2950 1250) $PN 205
J 2
(-2960 1260);
DISPLAY 0.617021 (-2960 1260);
PAINT ORANGE (-2960 1260);
FORCEPROP 2 LASTPIN (-2950 2050) $PN 58
J 2
(-2960 2060);
DISPLAY 0.617021 (-2960 2060);
PAINT ORANGE (-2960 2060);
FORCEPROP 2 LASTPIN (-2950 2100) $PN 222
J 2
(-2960 2110);
DISPLAY 0.617021 (-2960 2110);
PAINT ORANGE (-2960 2110);
FORCEPROP 2 LASTPIN (-2950 2700) $PN 91
J 2
(-2960 2710);
DISPLAY 0.617021 (-2960 2710);
PAINT ORANGE (-2960 2710);
FORCEPROP 2 LASTPIN (-2950 2650) $PN 87
J 2
(-2960 2660);
DISPLAY 0.617021 (-2960 2660);
PAINT ORANGE (-2960 2660);
FORCEPROP 2 LASTPIN (-2950 2000) $PN 78
J 2
(-2960 2010);
DISPLAY 0.617021 (-2960 2010);
PAINT ORANGE (-2960 2010);
FORCEPROP 2 LASTPIN (-1950 4600) $PN 280
J 0
(-1940 4610);
DISPLAY 0.617021 (-1940 4610);
PAINT ORANGE (-1940 4610);
FORCEPROP 2 LASTPIN (-1950 4550) $PN 135
J 0
(-1940 4560);
DISPLAY 0.617021 (-1940 4560);
PAINT ORANGE (-1940 4560);
FORCEPROP 2 LASTPIN (-1950 4500) $PN 273
J 0
(-1940 4510);
DISPLAY 0.617021 (-1940 4510);
PAINT ORANGE (-1940 4510);
FORCEPROP 2 LASTPIN (-1950 4450) $PN 128
J 0
(-1940 4460);
DISPLAY 0.617021 (-1940 4460);
PAINT ORANGE (-1940 4460);
FORCEPROP 2 LASTPIN (-1950 4400) $PN 282
J 0
(-1940 4410);
DISPLAY 0.617021 (-1940 4410);
PAINT ORANGE (-1940 4410);
FORCEPROP 2 LASTPIN (-1950 4350) $PN 137
J 0
(-1940 4360);
DISPLAY 0.617021 (-1940 4360);
PAINT ORANGE (-1940 4360);
FORCEPROP 2 LASTPIN (-1950 4300) $PN 275
J 0
(-1940 4310);
DISPLAY 0.617021 (-1940 4310);
PAINT ORANGE (-1940 4310);
FORCEPROP 2 LASTPIN (-1950 4250) $PN 130
J 0
(-1940 4260);
DISPLAY 0.617021 (-1940 4260);
PAINT ORANGE (-1940 4260);
FORCEPROP 2 LASTPIN (-1950 4200) $PN 269
J 0
(-1940 4210);
DISPLAY 0.617021 (-1940 4210);
PAINT ORANGE (-1940 4210);
FORCEPROP 2 LASTPIN (-1950 4150) $PN 124
J 0
(-1940 4160);
DISPLAY 0.617021 (-1940 4160);
PAINT ORANGE (-1940 4160);
FORCEPROP 2 LASTPIN (-1950 4100) $PN 262
J 0
(-1940 4110);
DISPLAY 0.617021 (-1940 4110);
PAINT ORANGE (-1940 4110);
FORCEPROP 2 LASTPIN (-1950 4050) $PN 117
J 0
(-1940 4060);
DISPLAY 0.617021 (-1940 4060);
PAINT ORANGE (-1940 4060);
FORCEPROP 2 LASTPIN (-1950 4000) $PN 271
J 0
(-1940 4010);
DISPLAY 0.617021 (-1940 4010);
PAINT ORANGE (-1940 4010);
FORCEPROP 2 LASTPIN (-1950 3950) $PN 126
J 0
(-1940 3960);
DISPLAY 0.617021 (-1940 3960);
PAINT ORANGE (-1940 3960);
FORCEPROP 2 LASTPIN (-1950 3900) $PN 264
J 0
(-1940 3910);
DISPLAY 0.617021 (-1940 3910);
PAINT ORANGE (-1940 3910);
FORCEPROP 2 LASTPIN (-1950 3850) $PN 119
J 0
(-1940 3860);
DISPLAY 0.617021 (-1940 3860);
PAINT ORANGE (-1940 3860);
FORCEPROP 2 LASTPIN (-1950 3800) $PN 258
J 0
(-1940 3810);
DISPLAY 0.617021 (-1940 3810);
PAINT ORANGE (-1940 3810);
FORCEPROP 2 LASTPIN (-1950 3750) $PN 113
J 0
(-1940 3760);
DISPLAY 0.617021 (-1940 3760);
PAINT ORANGE (-1940 3760);
FORCEPROP 2 LASTPIN (-1950 3700) $PN 251
J 0
(-1940 3710);
DISPLAY 0.617021 (-1940 3710);
PAINT ORANGE (-1940 3710);
FORCEPROP 2 LASTPIN (-1950 3650) $PN 106
J 0
(-1940 3660);
DISPLAY 0.617021 (-1940 3660);
PAINT ORANGE (-1940 3660);
FORCEPROP 2 LASTPIN (-1950 3600) $PN 260
J 0
(-1940 3610);
DISPLAY 0.617021 (-1940 3610);
PAINT ORANGE (-1940 3610);
FORCEPROP 2 LASTPIN (-1950 3550) $PN 115
J 0
(-1940 3560);
DISPLAY 0.617021 (-1940 3560);
PAINT ORANGE (-1940 3560);
FORCEPROP 2 LASTPIN (-1950 3500) $PN 253
J 0
(-1940 3510);
DISPLAY 0.617021 (-1940 3510);
PAINT ORANGE (-1940 3510);
FORCEPROP 2 LASTPIN (-1950 3450) $PN 108
J 0
(-1940 3460);
DISPLAY 0.617021 (-1940 3460);
PAINT ORANGE (-1940 3460);
FORCEPROP 2 LASTPIN (-1950 3400) $PN 247
J 0
(-1940 3410);
DISPLAY 0.617021 (-1940 3410);
PAINT ORANGE (-1940 3410);
FORCEPROP 2 LASTPIN (-1950 3350) $PN 102
J 0
(-1940 3360);
DISPLAY 0.617021 (-1940 3360);
PAINT ORANGE (-1940 3360);
FORCEPROP 2 LASTPIN (-1950 3300) $PN 240
J 0
(-1940 3310);
DISPLAY 0.617021 (-1940 3310);
PAINT ORANGE (-1940 3310);
FORCEPROP 2 LASTPIN (-1950 3250) $PN 95
J 0
(-1940 3260);
DISPLAY 0.617021 (-1940 3260);
PAINT ORANGE (-1940 3260);
FORCEPROP 2 LASTPIN (-1950 3200) $PN 249
J 0
(-1940 3210);
DISPLAY 0.617021 (-1940 3210);
PAINT ORANGE (-1940 3210);
FORCEPROP 2 LASTPIN (-1950 3150) $PN 104
J 0
(-1940 3160);
DISPLAY 0.617021 (-1940 3160);
PAINT ORANGE (-1940 3160);
FORCEPROP 2 LASTPIN (-1950 3100) $PN 242
J 0
(-1940 3110);
DISPLAY 0.617021 (-1940 3110);
PAINT ORANGE (-1940 3110);
FORCEPROP 2 LASTPIN (-1950 3050) $PN 97
J 0
(-1940 3060);
DISPLAY 0.617021 (-1940 3060);
PAINT ORANGE (-1940 3060);
FORCEPROP 2 LASTPIN (-1950 3000) $PN 188
J 0
(-1940 3010);
DISPLAY 0.617021 (-1940 3010);
PAINT ORANGE (-1940 3010);
FORCEPROP 2 LASTPIN (-1950 2950) $PN 43
J 0
(-1940 2960);
DISPLAY 0.617021 (-1940 2960);
PAINT ORANGE (-1940 2960);
FORCEPROP 2 LASTPIN (-1950 2900) $PN 181
J 0
(-1940 2910);
DISPLAY 0.617021 (-1940 2910);
PAINT ORANGE (-1940 2910);
FORCEPROP 2 LASTPIN (-1950 2850) $PN 36
J 0
(-1940 2860);
DISPLAY 0.617021 (-1940 2860);
PAINT ORANGE (-1940 2860);
FORCEPROP 2 LASTPIN (-1950 2800) $PN 190
J 0
(-1940 2810);
DISPLAY 0.617021 (-1940 2810);
PAINT ORANGE (-1940 2810);
FORCEPROP 2 LASTPIN (-1950 2750) $PN 45
J 0
(-1940 2760);
DISPLAY 0.617021 (-1940 2760);
PAINT ORANGE (-1940 2760);
FORCEPROP 2 LASTPIN (-1950 2700) $PN 183
J 0
(-1940 2710);
DISPLAY 0.617021 (-1940 2710);
PAINT ORANGE (-1940 2710);
FORCEPROP 2 LASTPIN (-1950 2650) $PN 38
J 0
(-1940 2660);
DISPLAY 0.617021 (-1940 2660);
PAINT ORANGE (-1940 2660);
FORCEPROP 2 LASTPIN (-1950 2600) $PN 177
J 0
(-1940 2610);
DISPLAY 0.617021 (-1940 2610);
PAINT ORANGE (-1940 2610);
FORCEPROP 2 LASTPIN (-1950 2550) $PN 32
J 0
(-1940 2560);
DISPLAY 0.617021 (-1940 2560);
PAINT ORANGE (-1940 2560);
FORCEPROP 2 LASTPIN (-1950 2500) $PN 170
J 0
(-1940 2510);
DISPLAY 0.617021 (-1940 2510);
PAINT ORANGE (-1940 2510);
FORCEPROP 2 LASTPIN (-1950 2450) $PN 25
J 0
(-1940 2460);
DISPLAY 0.617021 (-1940 2460);
PAINT ORANGE (-1940 2460);
FORCEPROP 2 LASTPIN (-1950 2400) $PN 179
J 0
(-1940 2410);
DISPLAY 0.617021 (-1940 2410);
PAINT ORANGE (-1940 2410);
FORCEPROP 2 LASTPIN (-1950 2350) $PN 34
J 0
(-1940 2360);
DISPLAY 0.617021 (-1940 2360);
PAINT ORANGE (-1940 2360);
FORCEPROP 2 LASTPIN (-1950 2300) $PN 172
J 0
(-1940 2310);
DISPLAY 0.617021 (-1940 2310);
PAINT ORANGE (-1940 2310);
FORCEPROP 2 LASTPIN (-1950 2250) $PN 27
J 0
(-1940 2260);
DISPLAY 0.617021 (-1940 2260);
PAINT ORANGE (-1940 2260);
FORCEPROP 2 LASTPIN (-1950 2200) $PN 166
J 0
(-1940 2210);
DISPLAY 0.617021 (-1940 2210);
PAINT ORANGE (-1940 2210);
FORCEPROP 2 LASTPIN (-1950 2150) $PN 21
J 0
(-1940 2160);
DISPLAY 0.617021 (-1940 2160);
PAINT ORANGE (-1940 2160);
FORCEPROP 2 LASTPIN (-1950 2100) $PN 159
J 0
(-1940 2110);
DISPLAY 0.617021 (-1940 2110);
PAINT ORANGE (-1940 2110);
FORCEPROP 2 LASTPIN (-1950 2050) $PN 14
J 0
(-1940 2060);
DISPLAY 0.617021 (-1940 2060);
PAINT ORANGE (-1940 2060);
FORCEPROP 2 LASTPIN (-1950 2000) $PN 168
J 0
(-1940 2010);
DISPLAY 0.617021 (-1940 2010);
PAINT ORANGE (-1940 2010);
FORCEPROP 2 LASTPIN (-1950 1950) $PN 23
J 0
(-1940 1960);
DISPLAY 0.617021 (-1940 1960);
PAINT ORANGE (-1940 1960);
FORCEPROP 2 LASTPIN (-1950 1900) $PN 161
J 0
(-1940 1910);
DISPLAY 0.617021 (-1940 1910);
PAINT ORANGE (-1940 1910);
FORCEPROP 2 LASTPIN (-1950 1850) $PN 16
J 0
(-1940 1860);
DISPLAY 0.617021 (-1940 1860);
PAINT ORANGE (-1940 1860);
FORCEPROP 2 LASTPIN (-1950 1800) $PN 155
J 0
(-1940 1810);
DISPLAY 0.617021 (-1940 1810);
PAINT ORANGE (-1940 1810);
FORCEPROP 2 LASTPIN (-1950 1750) $PN 10
J 0
(-1940 1760);
DISPLAY 0.617021 (-1940 1760);
PAINT ORANGE (-1940 1760);
FORCEPROP 2 LASTPIN (-1950 1700) $PN 148
J 0
(-1940 1710);
DISPLAY 0.617021 (-1940 1710);
PAINT ORANGE (-1940 1710);
FORCEPROP 2 LASTPIN (-1950 1650) $PN 3
J 0
(-1940 1660);
DISPLAY 0.617021 (-1940 1660);
PAINT ORANGE (-1940 1660);
FORCEPROP 2 LASTPIN (-1950 1600) $PN 157
J 0
(-1940 1610);
DISPLAY 0.617021 (-1940 1610);
PAINT ORANGE (-1940 1610);
FORCEPROP 2 LASTPIN (-1950 1550) $PN 12
J 0
(-1940 1560);
DISPLAY 0.617021 (-1940 1560);
PAINT ORANGE (-1940 1560);
FORCEPROP 2 LASTPIN (-1950 1500) $PN 150
J 0
(-1940 1510);
DISPLAY 0.617021 (-1940 1510);
PAINT ORANGE (-1940 1510);
FORCEPROP 2 LASTPIN (-1950 1450) $PN 5
J 0
(-1940 1460);
DISPLAY 0.617021 (-1940 1460);
PAINT ORANGE (-1940 1460);
FORCEPROP 2 LASTPIN (-2950 2850) $PN 203
J 2
(-2960 2860);
DISPLAY 0.617021 (-2960 2860);
PAINT ORANGE (-2960 2860);
FORCEPROP 2 LASTPIN (-2950 2800) $PN 60
J 2
(-2960 2810);
DISPLAY 0.617021 (-2960 2810);
PAINT ORANGE (-2960 2810);
FORCEPROP 2 LASTPIN (-2950 3400) $PN 218
J 2
(-2960 3410);
DISPLAY 0.617021 (-2960 3410);
PAINT ORANGE (-2960 3410);
FORCEPROP 2 LASTPIN (-2950 3350) $PN 219
J 2
(-2960 3360);
DISPLAY 0.617021 (-2960 3360);
PAINT ORANGE (-2960 3360);
FORCEPROP 2 LASTPIN (-2950 3300) $PN 74
J 2
(-2960 3310);
DISPLAY 0.617021 (-2960 3310);
PAINT ORANGE (-2960 3310);
FORCEPROP 2 LASTPIN (-2950 3250) $PN 75
J 2
(-2960 3260);
DISPLAY 0.617021 (-2960 3260);
PAINT ORANGE (-2960 3260);
FORCEPROP 2 LASTPIN (-2950 2550) $PN 199
J 2
(-2960 2560);
DISPLAY 0.617021 (-2960 2560);
PAINT ORANGE (-2960 2560);
FORCEPROP 2 LASTPIN (-2950 2500) $PN 54
J 2
(-2960 2510);
DISPLAY 0.617021 (-2960 2510);
PAINT ORANGE (-2960 2510);
FORCEPROP 2 LASTPIN (-2950 2450) $PN 192
J 2
(-2960 2460);
DISPLAY 0.617021 (-2960 2460);
PAINT ORANGE (-2960 2460);
FORCEPROP 2 LASTPIN (-2950 2400) $PN 47
J 2
(-2960 2410);
DISPLAY 0.617021 (-2960 2410);
PAINT ORANGE (-2960 2410);
FORCEPROP 2 LASTPIN (-2950 2350) $PN 201
J 2
(-2960 2360);
DISPLAY 0.617021 (-2960 2360);
PAINT ORANGE (-2960 2360);
FORCEPROP 2 LASTPIN (-2950 2300) $PN 56
J 2
(-2960 2310);
DISPLAY 0.617021 (-2960 2310);
PAINT ORANGE (-2960 2310);
FORCEPROP 2 LASTPIN (-2950 2250) $PN 194
J 2
(-2960 2260);
DISPLAY 0.617021 (-2960 2260);
PAINT ORANGE (-2960 2260);
FORCEPROP 2 LASTPIN (-2950 2200) $PN 49
J 2
(-2960 2210);
DISPLAY 0.617021 (-2960 2210);
PAINT ORANGE (-2960 2210);
FORCEPROP 2 LASTPIN (-2950 3150) $PN 235
J 2
(-2960 3160);
DISPLAY 0.617021 (-2960 3160);
PAINT ORANGE (-2960 3160);
FORCEPROP 2 LASTPIN (-2950 3550) $PN 207
J 2
(-2960 3560);
DISPLAY 0.617021 (-2960 3560);
PAINT ORANGE (-2960 3560);
FORCEPROP 2 LASTPIN (-2950 3500) $PN 63
J 2
(-2960 3510);
DISPLAY 0.617021 (-2960 3510);
PAINT ORANGE (-2960 3510);
FORCEPROP 2 LASTPIN (-2950 3650) $PN 224
J 2
(-2960 3660);
DISPLAY 0.617021 (-2960 3660);
PAINT ORANGE (-2960 3660);
FORCEPROP 2 LASTPIN (-2950 3600) $PN 81
J 2
(-2960 3610);
DISPLAY 0.617021 (-2960 3610);
PAINT ORANGE (-2960 3610);
FORCEPROP 2 LASTPIN (-2950 1950) $PN 208
J 2
(-2960 1960);
DISPLAY 0.617021 (-2960 1960);
PAINT ORANGE (-2960 1960);
FORCEPROP 2 LASTPIN (-2950 1900) $PN 62
J 2
(-2960 1910);
DISPLAY 0.617021 (-2960 1910);
PAINT ORANGE (-2960 1910);
FORCEPROP 2 LASTPIN (-2950 4600) $PN 234
J 2
(-2960 4610);
DISPLAY 0.617021 (-2960 4610);
PAINT ORANGE (-2960 4610);
FORCEPROP 2 LASTPIN (-2950 4550) $PN 82
J 2
(-2960 4560);
DISPLAY 0.617021 (-2960 4560);
PAINT ORANGE (-2960 4560);
FORCEPROP 2 LASTPIN (-2950 4500) $PN 86
J 2
(-2960 4510);
DISPLAY 0.617021 (-2960 4510);
PAINT ORANGE (-2960 4510);
FORCEPROP 2 LASTPIN (-2950 4450) $PN 228
J 2
(-2960 4460);
DISPLAY 0.617021 (-2960 4460);
PAINT ORANGE (-2960 4460);
FORCEPROP 2 LASTPIN (-2950 4400) $PN 232
J 2
(-2960 4410);
DISPLAY 0.617021 (-2960 4410);
PAINT ORANGE (-2960 4410);
FORCEPROP 2 LASTPIN (-2950 4350) $PN 65
J 2
(-2960 4360);
DISPLAY 0.617021 (-2960 4360);
PAINT ORANGE (-2960 4360);
FORCEPROP 2 LASTPIN (-2950 4300) $PN 210
J 2
(-2960 4310);
DISPLAY 0.617021 (-2960 4310);
PAINT ORANGE (-2960 4310);
FORCEPROP 2 LASTPIN (-2950 4250) $PN 225
J 2
(-2960 4260);
DISPLAY 0.617021 (-2960 4260);
PAINT ORANGE (-2960 4260);
FORCEPROP 2 LASTPIN (-2950 4200) $PN 66
J 2
(-2960 4210);
DISPLAY 0.617021 (-2960 4210);
PAINT ORANGE (-2960 4210);
FORCEPROP 2 LASTPIN (-2950 4150) $PN 68
J 2
(-2960 4160);
DISPLAY 0.617021 (-2960 4160);
PAINT ORANGE (-2960 4160);
FORCEPROP 2 LASTPIN (-2950 4100) $PN 211
J 2
(-2960 4110);
DISPLAY 0.617021 (-2960 4110);
PAINT ORANGE (-2960 4110);
FORCEPROP 2 LASTPIN (-2950 4050) $PN 69
J 2
(-2960 4060);
DISPLAY 0.617021 (-2960 4060);
PAINT ORANGE (-2960 4060);
FORCEPROP 2 LASTPIN (-2950 4000) $PN 213
J 2
(-2960 4010);
DISPLAY 0.617021 (-2960 4010);
PAINT ORANGE (-2960 4010);
FORCEPROP 2 LASTPIN (-2950 3950) $PN 214
J 2
(-2960 3960);
DISPLAY 0.617021 (-2960 3960);
PAINT ORANGE (-2960 3960);
FORCEPROP 2 LASTPIN (-2950 3900) $PN 71
J 2
(-2960 3910);
DISPLAY 0.617021 (-2960 3910);
PAINT ORANGE (-2960 3910);
FORCEPROP 2 LASTPIN (-2950 3850) $PN 216
J 2
(-2960 3860);
DISPLAY 0.617021 (-2960 3860);
PAINT ORANGE (-2960 3860);
FORCEPROP 2 LASTPIN (-2950 3800) $PN 72
J 2
(-2960 3810);
DISPLAY 0.617021 (-2960 3810);
PAINT ORANGE (-2960 3810);
FORCEPROP 2 LASTPIN (-2950 3750) $PN 79
J 2
(-2960 3760);
DISPLAY 0.617021 (-2960 3760);
PAINT ORANGE (-2960 3760);
FORCEPROP 1 LAST PART_NUMBER H44441-004
J 0
(-2900 950);
DISPLAY 0.617021 (-2900 950);
PAINT BLUE (-2900 950);
FORCEPROP 1 LAST LOCATION J4G2
J 0
(-2900 4850);
DISPLAY 0.617021 (-2900 4850);
PAINT AQUA (-2900 4850);
FORCEPROP 1 LAST PACK_TYPE PIP
J 0
(-2900 4900);
PAINT SKYBLUE (-2900 4900);
DISPLAY INVISIBLE (-2900 4900);
FORCEPROP 2 LAST BOM_COST MEM
J 0
(-2450 2950);
PAINT ORANGE (-2450 2950);
DISPLAY INVISIBLE (-2450 2950);
FORCEPROP 2 LAST CDS_LIB mstr_sconn
J 0
(-2450 2950);
PAINT ORANGE (-2450 2950);
DISPLAY INVISIBLE (-2450 2950);
FORCEPROP 2 LAST SEC_TYPE PIP
J 0
(-2900 4900);
DISPLAY 1.021277 (-2900 4900);
PAINT ORANGE (-2900 4900);
DISPLAY INVISIBLE (-2900 4900);
FORCEPROP 2 LAST SEC 1
J 0
(-2900 4900);
DISPLAY 0.680851 (-2900 4900);
PAINT MONO (-2900 4900);
DISPLAY INVISIBLE (-2900 4900);
FORCEPROP 2 LAST CDS_LOCATION J4G2
J 0
(-2900 4850);
DISPLAY 0.617021 (-2900 4850);
PAINT AQUA (-2900 4850);
DISPLAY INVISIBLE (-2900 4850);
FORCEPROP 1 LAST PATH I111
J 0
(-2450 4800);
PAINT GREEN (-2450 4800);
DISPLAY INVISIBLE (-2450 4800);
FORCEPROP 2 LAST ROOM DDR4_CH_B
J 0
(-2450 2950);
PAINT ORANGE (-2450 2950);
DISPLAY INVISIBLE (-2450 2950);
FORCEADD TAP..6
(-3200 4600);
FORCEPROP 3 LASTPIN (-3150 4600) SIG_NAME M_B_MA<17>
J 0
(-3140 4610);
DISPLAY 0.659574 (-3140 4610);
PAINT MONO (-3140 4610);
DISPLAY INVISIBLE (-3140 4610);
FORCEPROP 1 LASTPIN (-3150 4600) BN 17
J 0
(-3200 4610);
DISPLAY 0.617021 (-3200 4610);
PAINT PINK (-3200 4610);
FORCEPROP 2 LAST CDS_LIB mstr_standard
J 0
(-3200 4600);
DISPLAY 0.787234 (-3200 4600);
PAINT MONO (-3200 4600);
DISPLAY INVISIBLE (-3200 4600);
FORCEPROP 1 LAST BODY_TYPE PLUMBING
J 0
(-3200 4550);
DISPLAY 1.234043 (-3200 4550);
PAINT GREEN (-3200 4550);
DISPLAY INVISIBLE (-3200 4550);
FORCEPROP 1 LAST HDL_TAP TRUE
J 0
(-2875 4475);
DISPLAY 1.234043 (-2875 4475);
PAINT GREEN (-2875 4475);
DISPLAY INVISIBLE (-2875 4475);
FORCEPROP 1 LAST PATH I112
J 0
(-3200 4600);
DISPLAY 0.936170 (-3200 4600);
PAINT GREEN (-3200 4600);
DISPLAY INVISIBLE (-3200 4600);
FORCEADD TAP..6
(-3200 4550);
FORCEPROP 3 LASTPIN (-3150 4550) SIG_NAME M_B_MA<16>
J 0
(-3140 4560);
DISPLAY 0.659574 (-3140 4560);
PAINT MONO (-3140 4560);
DISPLAY INVISIBLE (-3140 4560);
FORCEPROP 1 LASTPIN (-3150 4550) BN 16
J 0
(-3200 4560);
DISPLAY 0.617021 (-3200 4560);
PAINT PINK (-3200 4560);
FORCEPROP 2 LAST CDS_LIB mstr_standard
J 2
(-3200 4550);
DISPLAY 0.787234 (-3200 4550);
PAINT MONO (-3200 4550);
DISPLAY INVISIBLE (-3200 4550);
FORCEPROP 1 LAST BODY_TYPE PLUMBING
J 0
(-3200 4500);
DISPLAY 1.234043 (-3200 4500);
PAINT GREEN (-3200 4500);
DISPLAY INVISIBLE (-3200 4500);
FORCEPROP 1 LAST HDL_TAP TRUE
J 0
(-2875 4425);
DISPLAY 1.234043 (-2875 4425);
PAINT GREEN (-2875 4425);
DISPLAY INVISIBLE (-2875 4425);
FORCEPROP 1 LAST PATH I113
J 0
(-3200 4550);
DISPLAY 0.936170 (-3200 4550);
PAINT GREEN (-3200 4550);
DISPLAY INVISIBLE (-3200 4550);
FORCEADD TAP..6
(-3200 4500);
FORCEPROP 3 LASTPIN (-3150 4500) SIG_NAME M_B_MA<15>
J 0
(-3140 4510);
DISPLAY 0.659574 (-3140 4510);
PAINT MONO (-3140 4510);
DISPLAY INVISIBLE (-3140 4510);
FORCEPROP 1 LASTPIN (-3150 4500) BN 15
J 0
(-3200 4510);
DISPLAY 0.617021 (-3200 4510);
PAINT PINK (-3200 4510);
FORCEPROP 2 LAST CDS_LIB mstr_standard
J 2
(-3200 4500);
DISPLAY 0.787234 (-3200 4500);
PAINT MONO (-3200 4500);
DISPLAY INVISIBLE (-3200 4500);
FORCEPROP 1 LAST BODY_TYPE PLUMBING
J 0
(-3200 4450);
DISPLAY 1.234043 (-3200 4450);
PAINT GREEN (-3200 4450);
DISPLAY INVISIBLE (-3200 4450);
FORCEPROP 1 LAST HDL_TAP TRUE
J 0
(-2875 4375);
DISPLAY 1.234043 (-2875 4375);
PAINT GREEN (-2875 4375);
DISPLAY INVISIBLE (-2875 4375);
FORCEPROP 1 LAST PATH I114
J 0
(-3200 4500);
DISPLAY 0.936170 (-3200 4500);
PAINT GREEN (-3200 4500);
DISPLAY INVISIBLE (-3200 4500);
FORCEADD TAP..6
(-3200 4450);
FORCEPROP 3 LASTPIN (-3150 4450) SIG_NAME M_B_MA<14>
J 0
(-3140 4460);
DISPLAY 0.659574 (-3140 4460);
PAINT MONO (-3140 4460);
DISPLAY INVISIBLE (-3140 4460);
FORCEPROP 1 LASTPIN (-3150 4450) BN 14
J 0
(-3200 4460);
DISPLAY 0.617021 (-3200 4460);
PAINT PINK (-3200 4460);
FORCEPROP 2 LAST CDS_LIB mstr_standard
J 2
(-3200 4450);
DISPLAY 0.787234 (-3200 4450);
PAINT MONO (-3200 4450);
DISPLAY INVISIBLE (-3200 4450);
FORCEPROP 1 LAST BODY_TYPE PLUMBING
J 0
(-3200 4400);
DISPLAY 1.234043 (-3200 4400);
PAINT GREEN (-3200 4400);
DISPLAY INVISIBLE (-3200 4400);
FORCEPROP 1 LAST HDL_TAP TRUE
J 0
(-2875 4325);
DISPLAY 1.234043 (-2875 4325);
PAINT GREEN (-2875 4325);
DISPLAY INVISIBLE (-2875 4325);
FORCEPROP 1 LAST PATH I115
J 0
(-3200 4450);
DISPLAY 0.936170 (-3200 4450);
PAINT GREEN (-3200 4450);
DISPLAY INVISIBLE (-3200 4450);
FORCEADD TAP..6
(-3200 4400);
FORCEPROP 3 LASTPIN (-3150 4400) SIG_NAME M_B_MA<13>
J 0
(-3140 4410);
DISPLAY 0.659574 (-3140 4410);
PAINT MONO (-3140 4410);
DISPLAY INVISIBLE (-3140 4410);
FORCEPROP 1 LASTPIN (-3150 4400) BN 13
J 0
(-3200 4410);
DISPLAY 0.617021 (-3200 4410);
PAINT PINK (-3200 4410);
FORCEPROP 2 LAST CDS_LIB mstr_standard
J 2
(-3200 4400);
DISPLAY 0.787234 (-3200 4400);
PAINT MONO (-3200 4400);
DISPLAY INVISIBLE (-3200 4400);
FORCEPROP 1 LAST BODY_TYPE PLUMBING
J 0
(-3200 4350);
DISPLAY 1.234043 (-3200 4350);
PAINT GREEN (-3200 4350);
DISPLAY INVISIBLE (-3200 4350);
FORCEPROP 1 LAST HDL_TAP TRUE
J 0
(-2875 4275);
DISPLAY 1.234043 (-2875 4275);
PAINT GREEN (-2875 4275);
DISPLAY INVISIBLE (-2875 4275);
FORCEPROP 1 LAST PATH I116
J 0
(-3200 4400);
DISPLAY 0.936170 (-3200 4400);
PAINT GREEN (-3200 4400);
DISPLAY INVISIBLE (-3200 4400);
FORCEADD TAP..6
(-3200 4350);
FORCEPROP 3 LASTPIN (-3150 4350) SIG_NAME M_B_MA<12>
J 0
(-3140 4360);
DISPLAY 0.659574 (-3140 4360);
PAINT MONO (-3140 4360);
DISPLAY INVISIBLE (-3140 4360);
FORCEPROP 1 LASTPIN (-3150 4350) BN 12
J 0
(-3200 4360);
DISPLAY 0.617021 (-3200 4360);
PAINT PINK (-3200 4360);
FORCEPROP 2 LAST CDS_LIB mstr_standard
J 2
(-3200 4350);
DISPLAY 0.787234 (-3200 4350);
PAINT MONO (-3200 4350);
DISPLAY INVISIBLE (-3200 4350);
FORCEPROP 1 LAST BODY_TYPE PLUMBING
J 0
(-3200 4300);
DISPLAY 1.234043 (-3200 4300);
PAINT GREEN (-3200 4300);
DISPLAY INVISIBLE (-3200 4300);
FORCEPROP 1 LAST HDL_TAP TRUE
J 0
(-2875 4225);
DISPLAY 1.234043 (-2875 4225);
PAINT GREEN (-2875 4225);
DISPLAY INVISIBLE (-2875 4225);
FORCEPROP 1 LAST PATH I117
J 0
(-3200 4350);
DISPLAY 0.936170 (-3200 4350);
PAINT GREEN (-3200 4350);
DISPLAY INVISIBLE (-3200 4350);
FORCEADD TAP..6
(-3200 4300);
FORCEPROP 3 LASTPIN (-3150 4300) SIG_NAME M_B_MA<11>
J 0
(-3140 4310);
DISPLAY 0.659574 (-3140 4310);
PAINT MONO (-3140 4310);
DISPLAY INVISIBLE (-3140 4310);
FORCEPROP 1 LASTPIN (-3150 4300) BN 11
J 0
(-3200 4310);
DISPLAY 0.617021 (-3200 4310);
PAINT PINK (-3200 4310);
FORCEPROP 2 LAST CDS_LIB mstr_standard
J 2
(-3200 4300);
DISPLAY 0.787234 (-3200 4300);
PAINT MONO (-3200 4300);
DISPLAY INVISIBLE (-3200 4300);
FORCEPROP 1 LAST BODY_TYPE PLUMBING
J 0
(-3200 4250);
DISPLAY 1.234043 (-3200 4250);
PAINT GREEN (-3200 4250);
DISPLAY INVISIBLE (-3200 4250);
FORCEPROP 1 LAST HDL_TAP TRUE
J 0
(-2875 4175);
DISPLAY 1.234043 (-2875 4175);
PAINT GREEN (-2875 4175);
DISPLAY INVISIBLE (-2875 4175);
FORCEPROP 1 LAST PATH I118
J 0
(-3200 4300);
DISPLAY 0.936170 (-3200 4300);
PAINT GREEN (-3200 4300);
DISPLAY INVISIBLE (-3200 4300);
FORCEADD TAP..6
(-3200 4250);
FORCEPROP 3 LASTPIN (-3150 4250) SIG_NAME M_B_MA<10>
J 0
(-3140 4260);
DISPLAY 0.659574 (-3140 4260);
PAINT MONO (-3140 4260);
DISPLAY INVISIBLE (-3140 4260);
FORCEPROP 1 LASTPIN (-3150 4250) BN 10
J 0
(-3200 4260);
DISPLAY 0.617021 (-3200 4260);
PAINT PINK (-3200 4260);
FORCEPROP 2 LAST CDS_LIB mstr_standard
J 2
(-3200 4250);
DISPLAY 0.787234 (-3200 4250);
PAINT MONO (-3200 4250);
DISPLAY INVISIBLE (-3200 4250);
FORCEPROP 1 LAST BODY_TYPE PLUMBING
J 0
(-3200 4200);
DISPLAY 1.234043 (-3200 4200);
PAINT GREEN (-3200 4200);
DISPLAY INVISIBLE (-3200 4200);
FORCEPROP 1 LAST HDL_TAP TRUE
J 0
(-2875 4125);
DISPLAY 1.234043 (-2875 4125);
PAINT GREEN (-2875 4125);
DISPLAY INVISIBLE (-2875 4125);
FORCEPROP 1 LAST PATH I119
J 0
(-3200 4250);
DISPLAY 0.936170 (-3200 4250);
PAINT GREEN (-3200 4250);
DISPLAY INVISIBLE (-3200 4250);
FORCEADD PVTT_ABC..1
(-800 2700);
FORCEPROP 3 LASTPIN (-800 2650) SIG_NAME PVTT_ABC\g
J 0
(-790 2660);
DISPLAY 0.659574 (-790 2660);
PAINT MONO (-790 2660);
DISPLAY INVISIBLE (-790 2660);
FORCEPROP 1 LAST VOLTAGE 0.6V
J 0
(-845 2657);
DISPLAY 0.340426 (-845 2657);
PAINT SKYBLUE (-845 2657);
DISPLAY INVISIBLE (-845 2657);
FORCEPROP 2 LAST BOM_COST MEM
J 0
(-800 2705);
PAINT ORANGE (-800 2705);
DISPLAY INVISIBLE (-800 2705);
FORCEPROP 2 LAST CDS_LIB mstr_symbols
J 0
(-800 2700);
PAINT ORANGE (-800 2700);
DISPLAY INVISIBLE (-800 2700);
FORCEPROP 1 LAST BODY_TYPE PLUMBING
J 0
(-845 2657);
DISPLAY 0.340426 (-845 2657);
PAINT GREEN (-845 2657);
DISPLAY INVISIBLE (-845 2657);
FORCEPROP 1 LAST PATH I12
J 0
(-750 2725);
DISPLAY 0.872340 (-750 2725);
PAINT AQUA (-750 2725);
DISPLAY INVISIBLE (-750 2725);
FORCEPROP 2 LAST ROOM DDR4_CH_A
J 0
(-800 2800);
DISPLAY 0.787234 (-800 2800);
PAINT ORANGE (-800 2800);
DISPLAY INVISIBLE (-800 2800);
FORCEPROP 1 LAST HDL_POWER PVTT_ABC
J 1
(-800 2750);
DISPLAY 0.872340 (-800 2750);
PAINT GREEN (-800 2750);
DISPLAY INVISIBLE (-800 2750);
FORCEADD TAP..6
(-3200 4200);
FORCEPROP 3 LASTPIN (-3150 4200) SIG_NAME M_B_MA<9>
J 0
(-3140 4210);
DISPLAY 0.659574 (-3140 4210);
PAINT MONO (-3140 4210);
DISPLAY INVISIBLE (-3140 4210);
FORCEPROP 1 LASTPIN (-3150 4200) BN 9
J 0
(-3200 4210);
DISPLAY 0.617021 (-3200 4210);
PAINT PINK (-3200 4210);
FORCEPROP 2 LAST CDS_LIB mstr_standard
J 2
(-3200 4200);
DISPLAY 0.787234 (-3200 4200);
PAINT MONO (-3200 4200);
DISPLAY INVISIBLE (-3200 4200);
FORCEPROP 1 LAST BODY_TYPE PLUMBING
J 0
(-3200 4150);
DISPLAY 1.234043 (-3200 4150);
PAINT GREEN (-3200 4150);
DISPLAY INVISIBLE (-3200 4150);
FORCEPROP 1 LAST HDL_TAP TRUE
J 0
(-2875 4075);
DISPLAY 1.234043 (-2875 4075);
PAINT GREEN (-2875 4075);
DISPLAY INVISIBLE (-2875 4075);
FORCEPROP 1 LAST PATH I120
J 0
(-3200 4200);
DISPLAY 0.936170 (-3200 4200);
PAINT GREEN (-3200 4200);
DISPLAY INVISIBLE (-3200 4200);
FORCEADD TAP..6
(-3200 4150);
FORCEPROP 3 LASTPIN (-3150 4150) SIG_NAME M_B_MA<8>
J 0
(-3140 4160);
DISPLAY 0.659574 (-3140 4160);
PAINT MONO (-3140 4160);
DISPLAY INVISIBLE (-3140 4160);
FORCEPROP 1 LASTPIN (-3150 4150) BN 8
J 0
(-3200 4160);
DISPLAY 0.617021 (-3200 4160);
PAINT PINK (-3200 4160);
FORCEPROP 2 LAST CDS_LIB mstr_standard
J 2
(-3200 4150);
DISPLAY 0.787234 (-3200 4150);
PAINT MONO (-3200 4150);
DISPLAY INVISIBLE (-3200 4150);
FORCEPROP 1 LAST BODY_TYPE PLUMBING
J 0
(-3200 4100);
DISPLAY 1.234043 (-3200 4100);
PAINT GREEN (-3200 4100);
DISPLAY INVISIBLE (-3200 4100);
FORCEPROP 1 LAST HDL_TAP TRUE
J 0
(-2875 4025);
DISPLAY 1.234043 (-2875 4025);
PAINT GREEN (-2875 4025);
DISPLAY INVISIBLE (-2875 4025);
FORCEPROP 1 LAST PATH I121
J 0
(-3200 4150);
DISPLAY 0.936170 (-3200 4150);
PAINT GREEN (-3200 4150);
DISPLAY INVISIBLE (-3200 4150);
FORCEADD TAP..6
(-3200 4100);
FORCEPROP 3 LASTPIN (-3150 4100) SIG_NAME M_B_MA<7>
J 0
(-3140 4110);
DISPLAY 0.659574 (-3140 4110);
PAINT MONO (-3140 4110);
DISPLAY INVISIBLE (-3140 4110);
FORCEPROP 1 LASTPIN (-3150 4100) BN 7
J 0
(-3200 4110);
DISPLAY 0.617021 (-3200 4110);
PAINT PINK (-3200 4110);
FORCEPROP 2 LAST CDS_LIB mstr_standard
J 2
(-3200 4100);
DISPLAY 0.787234 (-3200 4100);
PAINT MONO (-3200 4100);
DISPLAY INVISIBLE (-3200 4100);
FORCEPROP 1 LAST BODY_TYPE PLUMBING
J 0
(-3200 4050);
DISPLAY 1.234043 (-3200 4050);
PAINT GREEN (-3200 4050);
DISPLAY INVISIBLE (-3200 4050);
FORCEPROP 1 LAST HDL_TAP TRUE
J 0
(-2875 3975);
DISPLAY 1.234043 (-2875 3975);
PAINT GREEN (-2875 3975);
DISPLAY INVISIBLE (-2875 3975);
FORCEPROP 1 LAST PATH I122
J 0
(-3200 4100);
DISPLAY 0.936170 (-3200 4100);
PAINT GREEN (-3200 4100);
DISPLAY INVISIBLE (-3200 4100);
FORCEADD TAP..6
(-3200 4050);
FORCEPROP 3 LASTPIN (-3150 4050) SIG_NAME M_B_MA<6>
J 0
(-3140 4060);
DISPLAY 0.659574 (-3140 4060);
PAINT MONO (-3140 4060);
DISPLAY INVISIBLE (-3140 4060);
FORCEPROP 1 LASTPIN (-3150 4050) BN 6
J 0
(-3200 4060);
DISPLAY 0.617021 (-3200 4060);
PAINT PINK (-3200 4060);
FORCEPROP 2 LAST CDS_LIB mstr_standard
J 2
(-3200 4050);
DISPLAY 0.787234 (-3200 4050);
PAINT MONO (-3200 4050);
DISPLAY INVISIBLE (-3200 4050);
FORCEPROP 1 LAST BODY_TYPE PLUMBING
J 0
(-3200 4000);
DISPLAY 1.234043 (-3200 4000);
PAINT GREEN (-3200 4000);
DISPLAY INVISIBLE (-3200 4000);
FORCEPROP 1 LAST HDL_TAP TRUE
J 0
(-2875 3925);
DISPLAY 1.234043 (-2875 3925);
PAINT GREEN (-2875 3925);
DISPLAY INVISIBLE (-2875 3925);
FORCEPROP 1 LAST PATH I123
J 0
(-3200 4050);
DISPLAY 0.936170 (-3200 4050);
PAINT GREEN (-3200 4050);
DISPLAY INVISIBLE (-3200 4050);
FORCEADD TAP..6
(-3200 4000);
FORCEPROP 3 LASTPIN (-3150 4000) SIG_NAME M_B_MA<5>
J 0
(-3140 4010);
DISPLAY 0.659574 (-3140 4010);
PAINT MONO (-3140 4010);
DISPLAY INVISIBLE (-3140 4010);
FORCEPROP 1 LASTPIN (-3150 4000) BN 5
J 0
(-3200 4010);
DISPLAY 0.617021 (-3200 4010);
PAINT PINK (-3200 4010);
FORCEPROP 2 LAST CDS_LIB mstr_standard
J 2
(-3200 4000);
DISPLAY 0.787234 (-3200 4000);
PAINT MONO (-3200 4000);
DISPLAY INVISIBLE (-3200 4000);
FORCEPROP 1 LAST BODY_TYPE PLUMBING
J 0
(-3200 3950);
DISPLAY 1.234043 (-3200 3950);
PAINT GREEN (-3200 3950);
DISPLAY INVISIBLE (-3200 3950);
FORCEPROP 1 LAST HDL_TAP TRUE
J 0
(-2875 3875);
DISPLAY 1.234043 (-2875 3875);
PAINT GREEN (-2875 3875);
DISPLAY INVISIBLE (-2875 3875);
FORCEPROP 1 LAST PATH I124
J 0
(-3200 4000);
DISPLAY 0.936170 (-3200 4000);
PAINT GREEN (-3200 4000);
DISPLAY INVISIBLE (-3200 4000);
FORCEADD TAP..6
(-3200 3950);
FORCEPROP 3 LASTPIN (-3150 3950) SIG_NAME M_B_MA<4>
J 0
(-3140 3960);
DISPLAY 0.659574 (-3140 3960);
PAINT MONO (-3140 3960);
DISPLAY INVISIBLE (-3140 3960);
FORCEPROP 1 LASTPIN (-3150 3950) BN 4
J 0
(-3200 3960);
DISPLAY 0.617021 (-3200 3960);
PAINT PINK (-3200 3960);
FORCEPROP 2 LAST CDS_LIB mstr_standard
J 2
(-3200 3950);
DISPLAY 0.787234 (-3200 3950);
PAINT MONO (-3200 3950);
DISPLAY INVISIBLE (-3200 3950);
FORCEPROP 1 LAST BODY_TYPE PLUMBING
J 0
(-3200 3900);
DISPLAY 1.234043 (-3200 3900);
PAINT GREEN (-3200 3900);
DISPLAY INVISIBLE (-3200 3900);
FORCEPROP 1 LAST HDL_TAP TRUE
J 0
(-2875 3825);
DISPLAY 1.234043 (-2875 3825);
PAINT GREEN (-2875 3825);
DISPLAY INVISIBLE (-2875 3825);
FORCEPROP 1 LAST PATH I125
J 0
(-3200 3950);
DISPLAY 0.936170 (-3200 3950);
PAINT GREEN (-3200 3950);
DISPLAY INVISIBLE (-3200 3950);
FORCEADD TAP..6
(-3200 3900);
FORCEPROP 3 LASTPIN (-3150 3900) SIG_NAME M_B_MA<3>
J 0
(-3140 3910);
DISPLAY 0.659574 (-3140 3910);
PAINT MONO (-3140 3910);
DISPLAY INVISIBLE (-3140 3910);
FORCEPROP 1 LASTPIN (-3150 3900) BN 3
J 0
(-3200 3910);
DISPLAY 0.617021 (-3200 3910);
PAINT PINK (-3200 3910);
FORCEPROP 2 LAST CDS_LIB mstr_standard
J 2
(-3200 3900);
DISPLAY 0.787234 (-3200 3900);
PAINT MONO (-3200 3900);
DISPLAY INVISIBLE (-3200 3900);
FORCEPROP 1 LAST BODY_TYPE PLUMBING
J 0
(-3200 3850);
DISPLAY 1.234043 (-3200 3850);
PAINT GREEN (-3200 3850);
DISPLAY INVISIBLE (-3200 3850);
FORCEPROP 1 LAST HDL_TAP TRUE
J 0
(-2875 3775);
DISPLAY 1.234043 (-2875 3775);
PAINT GREEN (-2875 3775);
DISPLAY INVISIBLE (-2875 3775);
FORCEPROP 1 LAST PATH I126
J 0
(-3200 3900);
DISPLAY 0.936170 (-3200 3900);
PAINT GREEN (-3200 3900);
DISPLAY INVISIBLE (-3200 3900);
FORCEADD OFFPAGE..1
(-3850 4650);
FORCEPROP 2 LAST $XR1 46 
J 0
(-4191 4650);
DISPLAY 0.638298 (-4191 4650);
PAINT MONO (-4191 4650);
FORCEPROP 2 LAST $XR0 24 
J 0
(-4101 4650);
DISPLAY 0.638298 (-4101 4650);
PAINT MONO (-4101 4650);
FORCEPROP 2 LAST CDS_LIB mstr_standard
J 0
(-3850 4650);
DISPLAY 0.787234 (-3850 4650);
PAINT MONO (-3850 4650);
DISPLAY INVISIBLE (-3850 4650);
FORCEPROP 1 LAST OFFPAGE TRUE
J 0
(-3525 4525);
DISPLAY 0.936170 (-3525 4525);
PAINT GREEN (-3525 4525);
DISPLAY INVISIBLE (-3525 4525);
FORCEPROP 1 LAST COMMENT_BODY TRUE
J 0
(-3725 4550);
DISPLAY 0.936170 (-3725 4550);
PAINT GREEN (-3725 4550);
DISPLAY INVISIBLE (-3725 4550);
FORCEPROP 2 LAST PATH I127
J 0
(-3800 4725);
DISPLAY 0.787234 (-3800 4725);
PAINT MONO (-3800 4725);
DISPLAY INVISIBLE (-3800 4725);
FORCEADD TAP..6
(-3200 3850);
FORCEPROP 3 LASTPIN (-3150 3850) SIG_NAME M_B_MA<2>
J 0
(-3140 3860);
DISPLAY 0.659574 (-3140 3860);
PAINT MONO (-3140 3860);
DISPLAY INVISIBLE (-3140 3860);
FORCEPROP 1 LASTPIN (-3150 3850) BN 2
J 0
(-3200 3860);
DISPLAY 0.617021 (-3200 3860);
PAINT PINK (-3200 3860);
FORCEPROP 2 LAST CDS_LIB mstr_standard
J 2
(-3200 3850);
DISPLAY 0.787234 (-3200 3850);
PAINT MONO (-3200 3850);
DISPLAY INVISIBLE (-3200 3850);
FORCEPROP 1 LAST BODY_TYPE PLUMBING
J 0
(-3200 3800);
DISPLAY 1.234043 (-3200 3800);
PAINT GREEN (-3200 3800);
DISPLAY INVISIBLE (-3200 3800);
FORCEPROP 1 LAST HDL_TAP TRUE
J 0
(-2875 3725);
DISPLAY 1.234043 (-2875 3725);
PAINT GREEN (-2875 3725);
DISPLAY INVISIBLE (-2875 3725);
FORCEPROP 1 LAST PATH I128
J 0
(-3200 3850);
DISPLAY 0.936170 (-3200 3850);
PAINT GREEN (-3200 3850);
DISPLAY INVISIBLE (-3200 3850);
FORCEADD TAP..6
(-3200 3800);
FORCEPROP 3 LASTPIN (-3150 3800) SIG_NAME M_B_MA<1>
J 0
(-3140 3810);
DISPLAY 0.659574 (-3140 3810);
PAINT MONO (-3140 3810);
DISPLAY INVISIBLE (-3140 3810);
FORCEPROP 1 LASTPIN (-3150 3800) BN 1
J 0
(-3200 3810);
DISPLAY 0.617021 (-3200 3810);
PAINT PINK (-3200 3810);
FORCEPROP 2 LAST CDS_LIB mstr_standard
J 2
(-3200 3800);
DISPLAY 0.787234 (-3200 3800);
PAINT MONO (-3200 3800);
DISPLAY INVISIBLE (-3200 3800);
FORCEPROP 1 LAST BODY_TYPE PLUMBING
J 0
(-3200 3750);
DISPLAY 1.234043 (-3200 3750);
PAINT GREEN (-3200 3750);
DISPLAY INVISIBLE (-3200 3750);
FORCEPROP 1 LAST HDL_TAP TRUE
J 0
(-2875 3675);
DISPLAY 1.234043 (-2875 3675);
PAINT GREEN (-2875 3675);
DISPLAY INVISIBLE (-2875 3675);
FORCEPROP 1 LAST PATH I129
J 0
(-3200 3800);
DISPLAY 0.936170 (-3200 3800);
PAINT GREEN (-3200 3800);
DISPLAY INVISIBLE (-3200 3800);
FORCEADD PVDDQ_ABC..1
(-1025 2550);
FORCEPROP 3 LASTPIN (-1025 2500) SIG_NAME PVDDQ_ABC\g
J 0
(-1015 2510);
DISPLAY 0.659574 (-1015 2510);
PAINT MONO (-1015 2510);
DISPLAY INVISIBLE (-1015 2510);
FORCEPROP 1 LAST VOLTAGE 1.2V
J 0
(-1070 2507);
DISPLAY 0.340426 (-1070 2507);
PAINT SKYBLUE (-1070 2507);
DISPLAY INVISIBLE (-1070 2507);
FORCEPROP 2 LAST BOM_COST MEM
J 0
(-1025 2555);
PAINT ORANGE (-1025 2555);
DISPLAY INVISIBLE (-1025 2555);
FORCEPROP 2 LAST CDS_LIB mstr_symbols
J 0
(-1025 2550);
PAINT ORANGE (-1025 2550);
DISPLAY INVISIBLE (-1025 2550);
FORCEPROP 1 LAST BODY_TYPE PLUMBING
J 0
(-1070 2507);
DISPLAY 0.340426 (-1070 2507);
PAINT GREEN (-1070 2507);
DISPLAY INVISIBLE (-1070 2507);
FORCEPROP 1 LAST PATH I13
J 0
(-975 2575);
DISPLAY 0.872340 (-975 2575);
PAINT AQUA (-975 2575);
DISPLAY INVISIBLE (-975 2575);
FORCEPROP 2 LAST ROOM DDR4_CH_A
J 0
(-1025 2650);
DISPLAY 0.787234 (-1025 2650);
PAINT ORANGE (-1025 2650);
DISPLAY INVISIBLE (-1025 2650);
FORCEPROP 1 LAST HDL_POWER PVDDQ_ABC
J 1
(-1025 2600);
DISPLAY 0.872340 (-1025 2600);
PAINT GREEN (-1025 2600);
DISPLAY INVISIBLE (-1025 2600);
FORCEADD TAP..6
(-3200 3750);
FORCEPROP 3 LASTPIN (-3150 3750) SIG_NAME M_B_MA<0>
J 0
(-3140 3760);
DISPLAY 0.659574 (-3140 3760);
PAINT MONO (-3140 3760);
DISPLAY INVISIBLE (-3140 3760);
FORCEPROP 1 LASTPIN (-3150 3750) BN 0
J 0
(-3200 3760);
DISPLAY 0.617021 (-3200 3760);
PAINT PINK (-3200 3760);
FORCEPROP 2 LAST CDS_LIB mstr_standard
J 2
(-3200 3750);
DISPLAY 0.787234 (-3200 3750);
PAINT MONO (-3200 3750);
DISPLAY INVISIBLE (-3200 3750);
FORCEPROP 1 LAST BODY_TYPE PLUMBING
J 0
(-3200 3700);
DISPLAY 1.234043 (-3200 3700);
PAINT GREEN (-3200 3700);
DISPLAY INVISIBLE (-3200 3700);
FORCEPROP 1 LAST HDL_TAP TRUE
J 0
(-2875 3625);
DISPLAY 1.234043 (-2875 3625);
PAINT GREEN (-2875 3625);
DISPLAY INVISIBLE (-2875 3625);
FORCEPROP 1 LAST PATH I130
J 0
(-3200 3750);
DISPLAY 0.936170 (-3200 3750);
PAINT GREEN (-3200 3750);
DISPLAY INVISIBLE (-3200 3750);
FORCEADD TAP..6
(-3200 3650);
FORCEPROP 3 LASTPIN (-3150 3650) SIG_NAME M_B_BA<1>
J 0
(-3140 3660);
DISPLAY 0.659574 (-3140 3660);
PAINT MONO (-3140 3660);
DISPLAY INVISIBLE (-3140 3660);
FORCEPROP 1 LASTPIN (-3150 3650) BN 1
J 0
(-3200 3660);
DISPLAY 0.617021 (-3200 3660);
PAINT PINK (-3200 3660);
FORCEPROP 2 LAST CDS_LIB mstr_standard
J 0
(-3200 3650);
DISPLAY 0.787234 (-3200 3650);
PAINT MONO (-3200 3650);
DISPLAY INVISIBLE (-3200 3650);
FORCEPROP 1 LAST BODY_TYPE PLUMBING
J 0
(-3200 3600);
DISPLAY 1.234043 (-3200 3600);
PAINT GREEN (-3200 3600);
DISPLAY INVISIBLE (-3200 3600);
FORCEPROP 1 LAST HDL_TAP TRUE
J 0
(-2875 3525);
DISPLAY 1.234043 (-2875 3525);
PAINT GREEN (-2875 3525);
DISPLAY INVISIBLE (-2875 3525);
FORCEPROP 1 LAST PATH I131
J 0
(-3200 3650);
DISPLAY 0.936170 (-3200 3650);
PAINT GREEN (-3200 3650);
DISPLAY INVISIBLE (-3200 3650);
FORCEADD TAP..6
(-3200 3600);
FORCEPROP 3 LASTPIN (-3150 3600) SIG_NAME M_B_BA<0>
J 0
(-3140 3610);
DISPLAY 0.659574 (-3140 3610);
PAINT MONO (-3140 3610);
DISPLAY INVISIBLE (-3140 3610);
FORCEPROP 1 LASTPIN (-3150 3600) BN 0
J 0
(-3200 3610);
DISPLAY 0.617021 (-3200 3610);
PAINT PINK (-3200 3610);
FORCEPROP 2 LAST CDS_LIB mstr_standard
J 0
(-3200 3600);
DISPLAY 0.787234 (-3200 3600);
PAINT MONO (-3200 3600);
DISPLAY INVISIBLE (-3200 3600);
FORCEPROP 1 LAST BODY_TYPE PLUMBING
J 0
(-3200 3550);
DISPLAY 1.234043 (-3200 3550);
PAINT GREEN (-3200 3550);
DISPLAY INVISIBLE (-3200 3550);
FORCEPROP 1 LAST HDL_TAP TRUE
J 0
(-2875 3475);
DISPLAY 1.234043 (-2875 3475);
PAINT GREEN (-2875 3475);
DISPLAY INVISIBLE (-2875 3475);
FORCEPROP 1 LAST PATH I132
J 0
(-3200 3600);
DISPLAY 0.936170 (-3200 3600);
PAINT GREEN (-3200 3600);
DISPLAY INVISIBLE (-3200 3600);
FORCEADD TAP..6
(-3200 3500);
FORCEPROP 3 LASTPIN (-3150 3500) SIG_NAME M_B_BG<0>
J 0
(-3140 3510);
DISPLAY 0.659574 (-3140 3510);
PAINT MONO (-3140 3510);
DISPLAY INVISIBLE (-3140 3510);
FORCEPROP 1 LASTPIN (-3150 3500) BN 0
J 0
(-3200 3510);
DISPLAY 0.617021 (-3200 3510);
PAINT PINK (-3200 3510);
FORCEPROP 2 LAST CDS_LIB mstr_standard
J 0
(-3200 3500);
DISPLAY 0.787234 (-3200 3500);
PAINT MONO (-3200 3500);
DISPLAY INVISIBLE (-3200 3500);
FORCEPROP 1 LAST BODY_TYPE PLUMBING
J 0
(-3200 3450);
DISPLAY 1.234043 (-3200 3450);
PAINT GREEN (-3200 3450);
DISPLAY INVISIBLE (-3200 3450);
FORCEPROP 1 LAST HDL_TAP TRUE
J 0
(-2875 3375);
DISPLAY 1.234043 (-2875 3375);
PAINT GREEN (-2875 3375);
DISPLAY INVISIBLE (-2875 3375);
FORCEPROP 1 LAST PATH I133
J 0
(-3200 3500);
DISPLAY 0.936170 (-3200 3500);
PAINT GREEN (-3200 3500);
DISPLAY INVISIBLE (-3200 3500);
FORCEADD TAP..6
(-3200 3550);
FORCEPROP 3 LASTPIN (-3150 3550) SIG_NAME M_B_BG<1>
J 0
(-3140 3560);
DISPLAY 0.659574 (-3140 3560);
PAINT MONO (-3140 3560);
DISPLAY INVISIBLE (-3140 3560);
FORCEPROP 1 LASTPIN (-3150 3550) BN 1
J 0
(-3200 3560);
DISPLAY 0.617021 (-3200 3560);
PAINT PINK (-3200 3560);
FORCEPROP 2 LAST CDS_LIB mstr_standard
J 0
(-3200 3550);
DISPLAY 0.787234 (-3200 3550);
PAINT MONO (-3200 3550);
DISPLAY INVISIBLE (-3200 3550);
FORCEPROP 1 LAST BODY_TYPE PLUMBING
J 0
(-3200 3500);
DISPLAY 1.234043 (-3200 3500);
PAINT GREEN (-3200 3500);
DISPLAY INVISIBLE (-3200 3500);
FORCEPROP 1 LAST HDL_TAP TRUE
J 0
(-2875 3425);
DISPLAY 1.234043 (-2875 3425);
PAINT GREEN (-2875 3425);
DISPLAY INVISIBLE (-2875 3425);
FORCEPROP 1 LAST PATH I134
J 0
(-3200 3550);
DISPLAY 0.936170 (-3200 3550);
PAINT GREEN (-3200 3550);
DISPLAY INVISIBLE (-3200 3550);
FORCEADD OFFPAGE..1
(-3850 3200);
FORCEPROP 2 LAST $XR1 46 
J 0
(-4191 3200);
DISPLAY 0.638298 (-4191 3200);
PAINT MONO (-4191 3200);
FORCEPROP 2 LAST $XR0 24 
J 0
(-4101 3200);
DISPLAY 0.638298 (-4101 3200);
PAINT MONO (-4101 3200);
FORCEPROP 2 LAST CDS_LIB mstr_standard
J 0
(-3850 3200);
DISPLAY 0.787234 (-3850 3200);
PAINT MONO (-3850 3200);
DISPLAY INVISIBLE (-3850 3200);
FORCEPROP 1 LAST OFFPAGE TRUE
J 0
(-3525 3075);
DISPLAY 0.936170 (-3525 3075);
PAINT GREEN (-3525 3075);
DISPLAY INVISIBLE (-3525 3075);
FORCEPROP 1 LAST COMMENT_BODY TRUE
J 0
(-3725 3100);
DISPLAY 0.936170 (-3725 3100);
PAINT GREEN (-3725 3100);
DISPLAY INVISIBLE (-3725 3100);
FORCEPROP 2 LAST PATH I135
J 0
(-3800 3275);
DISPLAY 0.787234 (-3800 3275);
PAINT MONO (-3800 3275);
DISPLAY INVISIBLE (-3800 3275);
FORCEADD OFFPAGE..1
(-3850 3700);
FORCEPROP 2 LAST $XR1 46 
J 0
(-4191 3700);
DISPLAY 0.638298 (-4191 3700);
PAINT MONO (-4191 3700);
FORCEPROP 2 LAST $XR0 24 
J 0
(-4101 3700);
DISPLAY 0.638298 (-4101 3700);
PAINT MONO (-4101 3700);
FORCEPROP 2 LAST CDS_LIB mstr_standard
J 0
(-3850 3700);
DISPLAY 0.787234 (-3850 3700);
PAINT MONO (-3850 3700);
DISPLAY INVISIBLE (-3850 3700);
FORCEPROP 1 LAST OFFPAGE TRUE
J 0
(-3525 3575);
DISPLAY 0.936170 (-3525 3575);
PAINT GREEN (-3525 3575);
DISPLAY INVISIBLE (-3525 3575);
FORCEPROP 1 LAST COMMENT_BODY TRUE
J 0
(-3725 3600);
DISPLAY 0.936170 (-3725 3600);
PAINT GREEN (-3725 3600);
DISPLAY INVISIBLE (-3725 3600);
FORCEPROP 2 LAST PATH I136
J 0
(-3800 3775);
DISPLAY 0.787234 (-3800 3775);
PAINT MONO (-3800 3775);
DISPLAY INVISIBLE (-3800 3775);
FORCEADD OFFPAGE..1
(-3850 3600);
FORCEPROP 2 LAST $XR1 46 
J 0
(-4191 3600);
DISPLAY 0.638298 (-4191 3600);
PAINT MONO (-4191 3600);
FORCEPROP 2 LAST $XR0 24 
J 0
(-4101 3600);
DISPLAY 0.638298 (-4101 3600);
PAINT MONO (-4101 3600);
FORCEPROP 2 LAST CDS_LIB mstr_standard
J 0
(-3850 3600);
DISPLAY 0.787234 (-3850 3600);
PAINT MONO (-3850 3600);
DISPLAY INVISIBLE (-3850 3600);
FORCEPROP 1 LAST OFFPAGE TRUE
J 0
(-3525 3475);
DISPLAY 0.936170 (-3525 3475);
PAINT GREEN (-3525 3475);
DISPLAY INVISIBLE (-3525 3475);
FORCEPROP 1 LAST COMMENT_BODY TRUE
J 0
(-3725 3500);
DISPLAY 0.936170 (-3725 3500);
PAINT GREEN (-3725 3500);
DISPLAY INVISIBLE (-3725 3500);
FORCEPROP 2 LAST PATH I137
J 0
(-3800 3675);
DISPLAY 0.787234 (-3800 3675);
PAINT MONO (-3800 3675);
DISPLAY INVISIBLE (-3800 3675);
FORCEADD TAP..6
(-3200 2550);
FORCEPROP 3 LASTPIN (-3150 2550) SIG_NAME M_B_ECC<6>
J 0
(-3140 2560);
DISPLAY 0.659574 (-3140 2560);
PAINT MONO (-3140 2560);
DISPLAY INVISIBLE (-3140 2560);
FORCEPROP 1 LASTPIN (-3150 2550) BN 6
J 0
(-3200 2560);
DISPLAY 0.617021 (-3200 2560);
PAINT PINK (-3200 2560);
FORCEPROP 2 LAST CDS_LIB mstr_standard
J 0
(-3200 2550);
DISPLAY 0.787234 (-3200 2550);
PAINT MONO (-3200 2550);
DISPLAY INVISIBLE (-3200 2550);
FORCEPROP 1 LAST BODY_TYPE PLUMBING
J 0
(-3200 2500);
DISPLAY 1.234043 (-3200 2500);
PAINT GREEN (-3200 2500);
DISPLAY INVISIBLE (-3200 2500);
FORCEPROP 1 LAST HDL_TAP TRUE
J 0
(-2875 2425);
DISPLAY 1.234043 (-2875 2425);
PAINT GREEN (-2875 2425);
DISPLAY INVISIBLE (-2875 2425);
FORCEPROP 1 LAST PATH I138
J 0
(-3200 2550);
DISPLAY 0.936170 (-3200 2550);
PAINT GREEN (-3200 2550);
DISPLAY INVISIBLE (-3200 2550);
FORCEADD TAP..6
(-3200 2500);
FORCEPROP 3 LASTPIN (-3150 2500) SIG_NAME M_B_ECC<7>
J 0
(-3140 2510);
DISPLAY 0.659574 (-3140 2510);
PAINT MONO (-3140 2510);
DISPLAY INVISIBLE (-3140 2510);
FORCEPROP 1 LASTPIN (-3150 2500) BN 7
J 0
(-3200 2510);
DISPLAY 0.617021 (-3200 2510);
PAINT PINK (-3200 2510);
FORCEPROP 2 LAST CDS_LIB mstr_standard
J 0
(-3200 2500);
DISPLAY 0.787234 (-3200 2500);
PAINT MONO (-3200 2500);
DISPLAY INVISIBLE (-3200 2500);
FORCEPROP 1 LAST BODY_TYPE PLUMBING
J 0
(-3200 2450);
DISPLAY 1.234043 (-3200 2450);
PAINT GREEN (-3200 2450);
DISPLAY INVISIBLE (-3200 2450);
FORCEPROP 1 LAST HDL_TAP TRUE
J 0
(-2875 2375);
DISPLAY 1.234043 (-2875 2375);
PAINT GREEN (-2875 2375);
DISPLAY INVISIBLE (-2875 2375);
FORCEPROP 1 LAST PATH I139
J 0
(-3200 2500);
DISPLAY 0.936170 (-3200 2500);
PAINT GREEN (-3200 2500);
DISPLAY INVISIBLE (-3200 2500);
FORCEADD TAP..6
R 2
(900 4600);
FORCEPROP 3 LASTPIN (850 4600) SIG_NAME M_B_DQS_DN<12>
J 0
(860 4610);
DISPLAY 0.659574 (860 4610);
PAINT MONO (860 4610);
DISPLAY INVISIBLE (860 4610);
FORCEPROP 1 LASTPIN (850 4600) BN 12
J 2
(900 4610);
DISPLAY 0.617021 (900 4610);
PAINT PINK (900 4610);
FORCEPROP 2 LAST CDS_LIB mstr_standard
J 0
(900 4600);
DISPLAY 0.787234 (900 4600);
PAINT MONO (900 4600);
DISPLAY INVISIBLE (900 4600);
FORCEPROP 1 LAST BODY_TYPE PLUMBING
J 2
(900 4550);
DISPLAY 1.234043 (900 4550);
PAINT GREEN (900 4550);
DISPLAY INVISIBLE (900 4550);
FORCEPROP 1 LAST HDL_TAP TRUE
J 2
(575 4475);
DISPLAY 1.234043 (575 4475);
PAINT GREEN (575 4475);
DISPLAY INVISIBLE (575 4475);
FORCEPROP 1 LAST PATH I14
J 2
(900 4600);
DISPLAY 0.936170 (900 4600);
PAINT GREEN (900 4600);
DISPLAY INVISIBLE (900 4600);
FORCEADD TAP..6
(-3200 2450);
FORCEPROP 3 LASTPIN (-3150 2450) SIG_NAME M_B_ECC<4>
J 0
(-3140 2460);
DISPLAY 0.659574 (-3140 2460);
PAINT MONO (-3140 2460);
DISPLAY INVISIBLE (-3140 2460);
FORCEPROP 1 LASTPIN (-3150 2450) BN 4
J 0
(-3200 2460);
DISPLAY 0.617021 (-3200 2460);
PAINT PINK (-3200 2460);
FORCEPROP 2 LAST CDS_LIB mstr_standard
J 0
(-3200 2450);
DISPLAY 0.787234 (-3200 2450);
PAINT MONO (-3200 2450);
DISPLAY INVISIBLE (-3200 2450);
FORCEPROP 1 LAST BODY_TYPE PLUMBING
J 0
(-3200 2400);
DISPLAY 1.234043 (-3200 2400);
PAINT GREEN (-3200 2400);
DISPLAY INVISIBLE (-3200 2400);
FORCEPROP 1 LAST HDL_TAP TRUE
J 0
(-2875 2325);
DISPLAY 1.234043 (-2875 2325);
PAINT GREEN (-2875 2325);
DISPLAY INVISIBLE (-2875 2325);
FORCEPROP 1 LAST PATH I140
J 0
(-3200 2450);
DISPLAY 0.936170 (-3200 2450);
PAINT GREEN (-3200 2450);
DISPLAY INVISIBLE (-3200 2450);
FORCEADD TAP..6
(-3200 2400);
FORCEPROP 3 LASTPIN (-3150 2400) SIG_NAME M_B_ECC<5>
J 0
(-3140 2410);
DISPLAY 0.659574 (-3140 2410);
PAINT MONO (-3140 2410);
DISPLAY INVISIBLE (-3140 2410);
FORCEPROP 1 LASTPIN (-3150 2400) BN 5
J 0
(-3200 2410);
DISPLAY 0.617021 (-3200 2410);
PAINT PINK (-3200 2410);
FORCEPROP 2 LAST CDS_LIB mstr_standard
J 0
(-3200 2400);
DISPLAY 0.787234 (-3200 2400);
PAINT MONO (-3200 2400);
DISPLAY INVISIBLE (-3200 2400);
FORCEPROP 1 LAST BODY_TYPE PLUMBING
J 0
(-3200 2350);
DISPLAY 1.234043 (-3200 2350);
PAINT GREEN (-3200 2350);
DISPLAY INVISIBLE (-3200 2350);
FORCEPROP 1 LAST HDL_TAP TRUE
J 0
(-2875 2275);
DISPLAY 1.234043 (-2875 2275);
PAINT GREEN (-2875 2275);
DISPLAY INVISIBLE (-2875 2275);
FORCEPROP 1 LAST PATH I141
J 0
(-3200 2400);
DISPLAY 0.936170 (-3200 2400);
PAINT GREEN (-3200 2400);
DISPLAY INVISIBLE (-3200 2400);
FORCEADD TAP..6
(-3200 2350);
FORCEPROP 3 LASTPIN (-3150 2350) SIG_NAME M_B_ECC<2>
J 0
(-3140 2360);
DISPLAY 0.659574 (-3140 2360);
PAINT MONO (-3140 2360);
DISPLAY INVISIBLE (-3140 2360);
FORCEPROP 1 LASTPIN (-3150 2350) BN 2
J 0
(-3200 2360);
DISPLAY 0.617021 (-3200 2360);
PAINT PINK (-3200 2360);
FORCEPROP 2 LAST CDS_LIB mstr_standard
J 0
(-3200 2350);
DISPLAY 0.787234 (-3200 2350);
PAINT MONO (-3200 2350);
DISPLAY INVISIBLE (-3200 2350);
FORCEPROP 1 LAST BODY_TYPE PLUMBING
J 0
(-3200 2300);
DISPLAY 1.234043 (-3200 2300);
PAINT GREEN (-3200 2300);
DISPLAY INVISIBLE (-3200 2300);
FORCEPROP 1 LAST HDL_TAP TRUE
J 0
(-2875 2225);
DISPLAY 1.234043 (-2875 2225);
PAINT GREEN (-2875 2225);
DISPLAY INVISIBLE (-2875 2225);
FORCEPROP 1 LAST PATH I142
J 0
(-3200 2350);
DISPLAY 0.936170 (-3200 2350);
PAINT GREEN (-3200 2350);
DISPLAY INVISIBLE (-3200 2350);
FORCEADD TAP..6
(-3200 2300);
FORCEPROP 3 LASTPIN (-3150 2300) SIG_NAME M_B_ECC<3>
J 0
(-3140 2310);
DISPLAY 0.659574 (-3140 2310);
PAINT MONO (-3140 2310);
DISPLAY INVISIBLE (-3140 2310);
FORCEPROP 1 LASTPIN (-3150 2300) BN 3
J 0
(-3200 2310);
DISPLAY 0.617021 (-3200 2310);
PAINT PINK (-3200 2310);
FORCEPROP 2 LAST CDS_LIB mstr_standard
J 0
(-3200 2300);
DISPLAY 0.787234 (-3200 2300);
PAINT MONO (-3200 2300);
DISPLAY INVISIBLE (-3200 2300);
FORCEPROP 1 LAST BODY_TYPE PLUMBING
J 0
(-3200 2250);
DISPLAY 1.234043 (-3200 2250);
PAINT GREEN (-3200 2250);
DISPLAY INVISIBLE (-3200 2250);
FORCEPROP 1 LAST HDL_TAP TRUE
J 0
(-2875 2175);
DISPLAY 1.234043 (-2875 2175);
PAINT GREEN (-2875 2175);
DISPLAY INVISIBLE (-2875 2175);
FORCEPROP 1 LAST PATH I143
J 0
(-3200 2300);
DISPLAY 0.936170 (-3200 2300);
PAINT GREEN (-3200 2300);
DISPLAY INVISIBLE (-3200 2300);
FORCEADD TAP..6
(-3200 2250);
FORCEPROP 3 LASTPIN (-3150 2250) SIG_NAME M_B_ECC<0>
J 0
(-3140 2260);
DISPLAY 0.659574 (-3140 2260);
PAINT MONO (-3140 2260);
DISPLAY INVISIBLE (-3140 2260);
FORCEPROP 1 LASTPIN (-3150 2250) BN 0
J 0
(-3200 2260);
DISPLAY 0.617021 (-3200 2260);
PAINT PINK (-3200 2260);
FORCEPROP 2 LAST CDS_LIB mstr_standard
J 0
(-3200 2250);
DISPLAY 0.787234 (-3200 2250);
PAINT MONO (-3200 2250);
DISPLAY INVISIBLE (-3200 2250);
FORCEPROP 1 LAST BODY_TYPE PLUMBING
J 0
(-3200 2200);
DISPLAY 1.234043 (-3200 2200);
PAINT GREEN (-3200 2200);
DISPLAY INVISIBLE (-3200 2200);
FORCEPROP 1 LAST HDL_TAP TRUE
J 0
(-2875 2125);
DISPLAY 1.234043 (-2875 2125);
PAINT GREEN (-2875 2125);
DISPLAY INVISIBLE (-2875 2125);
FORCEPROP 1 LAST PATH I144
J 0
(-3200 2250);
DISPLAY 0.936170 (-3200 2250);
PAINT GREEN (-3200 2250);
DISPLAY INVISIBLE (-3200 2250);
FORCEADD TAP..6
(-3200 2200);
FORCEPROP 3 LASTPIN (-3150 2200) SIG_NAME M_B_ECC<1>
J 0
(-3140 2210);
DISPLAY 0.659574 (-3140 2210);
PAINT MONO (-3140 2210);
DISPLAY INVISIBLE (-3140 2210);
FORCEPROP 1 LASTPIN (-3150 2200) BN 1
J 0
(-3200 2210);
DISPLAY 0.617021 (-3200 2210);
PAINT PINK (-3200 2210);
FORCEPROP 2 LAST CDS_LIB mstr_standard
J 0
(-3200 2200);
DISPLAY 0.787234 (-3200 2200);
PAINT MONO (-3200 2200);
DISPLAY INVISIBLE (-3200 2200);
FORCEPROP 1 LAST BODY_TYPE PLUMBING
J 0
(-3200 2150);
DISPLAY 1.234043 (-3200 2150);
PAINT GREEN (-3200 2150);
DISPLAY INVISIBLE (-3200 2150);
FORCEPROP 1 LAST HDL_TAP TRUE
J 0
(-2875 2075);
DISPLAY 1.234043 (-2875 2075);
PAINT GREEN (-2875 2075);
DISPLAY INVISIBLE (-2875 2075);
FORCEPROP 1 LAST PATH I145
J 0
(-3200 2200);
DISPLAY 0.936170 (-3200 2200);
PAINT GREEN (-3200 2200);
DISPLAY INVISIBLE (-3200 2200);
FORCEADD OFFPAGE..1
(-3850 2550);
FORCEPROP 2 LAST $XR1 46 
J 0
(-4191 2550);
DISPLAY 0.638298 (-4191 2550);
PAINT MONO (-4191 2550);
FORCEPROP 2 LAST $XR0 24 
J 0
(-4101 2550);
DISPLAY 0.638298 (-4101 2550);
PAINT MONO (-4101 2550);
FORCEPROP 2 LAST CDS_LIB mstr_standard
J 0
(-3850 2550);
DISPLAY 0.787234 (-3850 2550);
PAINT MONO (-3850 2550);
DISPLAY INVISIBLE (-3850 2550);
FORCEPROP 1 LAST OFFPAGE TRUE
J 0
(-3525 2425);
DISPLAY 0.936170 (-3525 2425);
PAINT GREEN (-3525 2425);
DISPLAY INVISIBLE (-3525 2425);
FORCEPROP 1 LAST COMMENT_BODY TRUE
J 0
(-3725 2450);
DISPLAY 0.936170 (-3725 2450);
PAINT GREEN (-3725 2450);
DISPLAY INVISIBLE (-3725 2450);
FORCEPROP 2 LAST PATH I146
J 0
(-3800 2625);
DISPLAY 0.787234 (-3800 2625);
PAINT MONO (-3800 2625);
DISPLAY INVISIBLE (-3800 2625);
FORCEADD OFFPAGE..1
(-3850 2500);
FORCEPROP 2 LAST $XR5 48 
J 0
(-4551 2500);
DISPLAY 0.638298 (-4551 2500);
PAINT MONO (-4551 2500);
FORCEPROP 2 LAST $XR4 47 
J 0
(-4461 2500);
DISPLAY 0.638298 (-4461 2500);
PAINT MONO (-4461 2500);
FORCEPROP 2 LAST $XR3 46 
J 0
(-4371 2500);
DISPLAY 0.638298 (-4371 2500);
PAINT MONO (-4371 2500);
FORCEPROP 2 LAST $XR2 44 
J 0
(-4281 2500);
DISPLAY 0.638298 (-4281 2500);
PAINT MONO (-4281 2500);
FORCEPROP 2 LAST $XR1 43 
J 0
(-4191 2500);
DISPLAY 0.638298 (-4191 2500);
PAINT MONO (-4191 2500);
FORCEPROP 2 LAST $XR0 21 
J 0
(-4101 2500);
DISPLAY 0.638298 (-4101 2500);
PAINT MONO (-4101 2500);
FORCEPROP 2 LAST CDS_LIB mstr_standard
J 0
(-3850 2500);
DISPLAY 0.787234 (-3850 2500);
PAINT MONO (-3850 2500);
DISPLAY INVISIBLE (-3850 2500);
FORCEPROP 1 LAST OFFPAGE TRUE
J 0
(-3525 2375);
DISPLAY 0.936170 (-3525 2375);
PAINT GREEN (-3525 2375);
DISPLAY INVISIBLE (-3525 2375);
FORCEPROP 1 LAST COMMENT_BODY TRUE
J 0
(-3725 2400);
DISPLAY 0.936170 (-3725 2400);
PAINT GREEN (-3725 2400);
DISPLAY INVISIBLE (-3725 2400);
FORCEPROP 2 LAST PATH I147
J 0
(-3800 2575);
DISPLAY 0.787234 (-3800 2575);
PAINT MONO (-3800 2575);
DISPLAY INVISIBLE (-3800 2575);
FORCEADD OFFPAGE..5
(-4025 1950);
FORCEPROP 2 LAST $XR1 24 
J 0
(-4339 1950);
DISPLAY 0.638298 (-4339 1950);
PAINT MONO (-4339 1950);
FORCEPROP 2 LAST $XR0 46 
J 0
(-4249 1950);
DISPLAY 0.638298 (-4249 1950);
PAINT MONO (-4249 1950);
FORCEPROP 2 LAST CDS_LIB mstr_standard
J 0
(-4025 1950);
DISPLAY 0.787234 (-4025 1950);
PAINT MONO (-4025 1950);
DISPLAY INVISIBLE (-4025 1950);
FORCEPROP 1 LAST OFFPAGE TRUE
J 0
(-3700 1825);
DISPLAY 1.404255 (-3700 1825);
PAINT GREEN (-3700 1825);
DISPLAY INVISIBLE (-3700 1825);
FORCEPROP 1 LAST COMMENT_BODY TRUE
J 0
(-3925 1875);
DISPLAY 1.404255 (-3925 1875);
PAINT GREEN (-3925 1875);
DISPLAY INVISIBLE (-3925 1875);
FORCEPROP 2 LAST PATH I148
J 0
(-3975 2025);
DISPLAY 0.787234 (-3975 2025);
PAINT MONO (-3975 2025);
DISPLAY INVISIBLE (-3975 2025);
FORCEADD OFFPAGE..1
(-4000 1900);
FORCEPROP 2 LAST $XR1 46 
J 0
(-4341 1900);
DISPLAY 0.638298 (-4341 1900);
PAINT MONO (-4341 1900);
FORCEPROP 2 LAST $XR0 24 
J 0
(-4251 1900);
DISPLAY 0.638298 (-4251 1900);
PAINT MONO (-4251 1900);
FORCEPROP 2 LAST CDS_LIB mstr_standard
J 0
(-4000 1900);
DISPLAY 0.787234 (-4000 1900);
PAINT MONO (-4000 1900);
DISPLAY INVISIBLE (-4000 1900);
FORCEPROP 1 LAST OFFPAGE TRUE
J 0
(-3675 1775);
DISPLAY 0.936170 (-3675 1775);
PAINT GREEN (-3675 1775);
DISPLAY INVISIBLE (-3675 1775);
FORCEPROP 1 LAST COMMENT_BODY TRUE
J 0
(-3875 1800);
DISPLAY 0.936170 (-3875 1800);
PAINT GREEN (-3875 1800);
DISPLAY INVISIBLE (-3875 1800);
FORCEPROP 2 LAST PATH I149
J 0
(-3950 1975);
DISPLAY 0.787234 (-3950 1975);
PAINT MONO (-3950 1975);
DISPLAY INVISIBLE (-3950 1975);
FORCEADD TAP..6
R 2
(900 4700);
FORCEPROP 3 LASTPIN (850 4700) SIG_NAME M_B_DQS_DN<13>
J 0
(860 4710);
DISPLAY 0.659574 (860 4710);
PAINT MONO (860 4710);
DISPLAY INVISIBLE (860 4710);
FORCEPROP 1 LASTPIN (850 4700) BN 13
J 2
(900 4710);
DISPLAY 0.617021 (900 4710);
PAINT PINK (900 4710);
FORCEPROP 2 LAST CDS_LIB mstr_standard
J 0
(900 4700);
DISPLAY 0.787234 (900 4700);
PAINT MONO (900 4700);
DISPLAY INVISIBLE (900 4700);
FORCEPROP 1 LAST BODY_TYPE PLUMBING
J 2
(900 4650);
DISPLAY 1.234043 (900 4650);
PAINT GREEN (900 4650);
DISPLAY INVISIBLE (900 4650);
FORCEPROP 1 LAST HDL_TAP TRUE
J 2
(575 4575);
DISPLAY 1.234043 (575 4575);
PAINT GREEN (575 4575);
DISPLAY INVISIBLE (575 4575);
FORCEPROP 1 LAST PATH I15
J 2
(900 4700);
DISPLAY 0.936170 (900 4700);
PAINT GREEN (900 4700);
DISPLAY INVISIBLE (900 4700);
FORCEADD OFFPAGE..6
(-3850 2600);
FORCEPROP 2 LAST $XR1 46 
J 0
(-4189 2600);
DISPLAY 0.638298 (-4189 2600);
PAINT MONO (-4189 2600);
FORCEPROP 2 LAST $XR0 24 
J 0
(-4099 2600);
DISPLAY 0.638298 (-4099 2600);
PAINT MONO (-4099 2600);
FORCEPROP 2 LAST CDS_LIB mstr_standard
J 0
(-3850 2600);
DISPLAY 0.787234 (-3850 2600);
PAINT MONO (-3850 2600);
DISPLAY INVISIBLE (-3850 2600);
FORCEPROP 1 LAST OFFPAGE TRUE
J 0
(-3525 2475);
DISPLAY 0.936170 (-3525 2475);
PAINT GREEN (-3525 2475);
DISPLAY INVISIBLE (-3525 2475);
FORCEPROP 1 LAST COMMENT_BODY TRUE
J 0
(-3750 2525);
DISPLAY 0.936170 (-3750 2525);
PAINT GREEN (-3750 2525);
DISPLAY INVISIBLE (-3750 2525);
FORCEPROP 2 LAST PATH I150
J 0
(-3800 2675);
DISPLAY 0.787234 (-3800 2675);
PAINT MONO (-3800 2675);
DISPLAY INVISIBLE (-3800 2675);
FORCEADD OFFPAGE..1
(-4750 1450);
FORCEPROP 2 LAST $XR1 46 
J 0
(-5061 1450);
DISPLAY 0.638298 (-5061 1450);
PAINT MONO (-5061 1450);
FORCEPROP 2 LAST $XR0 98 
J 0
(-4971 1450);
DISPLAY 0.638298 (-4971 1450);
PAINT MONO (-4971 1450);
FORCEPROP 2 LAST CDS_LIB mstr_standard
J 0
(-4750 1450);
DISPLAY 0.787234 (-4750 1450);
PAINT MONO (-4750 1450);
DISPLAY INVISIBLE (-4750 1450);
FORCEPROP 1 LAST OFFPAGE TRUE
J 0
(-4425 1325);
DISPLAY 0.936170 (-4425 1325);
PAINT GREEN (-4425 1325);
DISPLAY INVISIBLE (-4425 1325);
FORCEPROP 1 LAST COMMENT_BODY TRUE
J 0
(-4625 1350);
DISPLAY 0.936170 (-4625 1350);
PAINT GREEN (-4625 1350);
DISPLAY INVISIBLE (-4625 1350);
FORCEPROP 2 LAST PATH I151
J 0
(-4700 1525);
DISPLAY 0.787234 (-4700 1525);
PAINT MONO (-4700 1525);
DISPLAY INVISIBLE (-4700 1525);
FORCEADD TAP..6
(-3200 2700);
FORCEPROP 3 LASTPIN (-3150 2700) SIG_NAME M_B_ODT<1>
J 0
(-3140 2710);
DISPLAY 0.659574 (-3140 2710);
PAINT MONO (-3140 2710);
DISPLAY INVISIBLE (-3140 2710);
FORCEPROP 1 LASTPIN (-3150 2700) BN 1
J 0
(-3200 2710);
DISPLAY 0.617021 (-3200 2710);
PAINT PINK (-3200 2710);
FORCEPROP 2 LAST CDS_LIB mstr_standard
J 0
(-3200 2700);
DISPLAY 0.787234 (-3200 2700);
PAINT MONO (-3200 2700);
DISPLAY INVISIBLE (-3200 2700);
FORCEPROP 1 LAST BODY_TYPE PLUMBING
J 0
(-3200 2650);
DISPLAY 1.234043 (-3200 2650);
PAINT GREEN (-3200 2650);
DISPLAY INVISIBLE (-3200 2650);
FORCEPROP 1 LAST HDL_TAP TRUE
J 0
(-2875 2575);
DISPLAY 1.234043 (-2875 2575);
PAINT GREEN (-2875 2575);
DISPLAY INVISIBLE (-2875 2575);
FORCEPROP 1 LAST PATH I152
J 0
(-3200 2700);
DISPLAY 0.936170 (-3200 2700);
PAINT GREEN (-3200 2700);
DISPLAY INVISIBLE (-3200 2700);
FORCEADD TAP..6
(-3200 2650);
FORCEPROP 3 LASTPIN (-3150 2650) SIG_NAME M_B_ODT<0>
J 0
(-3140 2660);
DISPLAY 0.659574 (-3140 2660);
PAINT MONO (-3140 2660);
DISPLAY INVISIBLE (-3140 2660);
FORCEPROP 1 LASTPIN (-3150 2650) BN 0
J 0
(-3200 2660);
DISPLAY 0.617021 (-3200 2660);
PAINT PINK (-3200 2660);
FORCEPROP 2 LAST CDS_LIB mstr_standard
J 0
(-3200 2650);
DISPLAY 0.787234 (-3200 2650);
PAINT MONO (-3200 2650);
DISPLAY INVISIBLE (-3200 2650);
FORCEPROP 1 LAST BODY_TYPE PLUMBING
J 0
(-3200 2600);
DISPLAY 1.234043 (-3200 2600);
PAINT GREEN (-3200 2600);
DISPLAY INVISIBLE (-3200 2600);
FORCEPROP 1 LAST HDL_TAP TRUE
J 0
(-2875 2525);
DISPLAY 1.234043 (-2875 2525);
PAINT GREEN (-2875 2525);
DISPLAY INVISIBLE (-2875 2525);
FORCEPROP 1 LAST PATH I153
J 0
(-3200 2650);
DISPLAY 0.936170 (-3200 2650);
PAINT GREEN (-3200 2650);
DISPLAY INVISIBLE (-3200 2650);
FORCEADD OFFPAGE..1
(-3850 2800);
FORCEPROP 2 LAST $XR1 46 
J 0
(-4191 2800);
DISPLAY 0.638298 (-4191 2800);
PAINT MONO (-4191 2800);
FORCEPROP 2 LAST $XR0 24 
J 0
(-4101 2800);
DISPLAY 0.638298 (-4101 2800);
PAINT MONO (-4101 2800);
FORCEPROP 2 LAST CDS_LIB mstr_standard
J 0
(-3850 2800);
DISPLAY 0.787234 (-3850 2800);
PAINT MONO (-3850 2800);
DISPLAY INVISIBLE (-3850 2800);
FORCEPROP 1 LAST OFFPAGE TRUE
J 0
(-3525 2675);
DISPLAY 0.936170 (-3525 2675);
PAINT GREEN (-3525 2675);
DISPLAY INVISIBLE (-3525 2675);
FORCEPROP 1 LAST COMMENT_BODY TRUE
J 0
(-3725 2700);
DISPLAY 0.936170 (-3725 2700);
PAINT GREEN (-3725 2700);
DISPLAY INVISIBLE (-3725 2700);
FORCEPROP 2 LAST PATH I154
J 0
(-3800 2875);
DISPLAY 0.787234 (-3800 2875);
PAINT MONO (-3800 2875);
DISPLAY INVISIBLE (-3800 2875);
FORCEADD TAP..6
(-3200 2850);
FORCEPROP 3 LASTPIN (-3150 2850) SIG_NAME M_B_CKE<1>
J 0
(-3140 2860);
DISPLAY 0.659574 (-3140 2860);
PAINT MONO (-3140 2860);
DISPLAY INVISIBLE (-3140 2860);
FORCEPROP 1 LASTPIN (-3150 2850) BN 1
J 0
(-3200 2860);
DISPLAY 0.617021 (-3200 2860);
PAINT PINK (-3200 2860);
FORCEPROP 2 LAST CDS_LIB mstr_standard
J 0
(-3200 2850);
DISPLAY 0.787234 (-3200 2850);
PAINT MONO (-3200 2850);
DISPLAY INVISIBLE (-3200 2850);
FORCEPROP 1 LAST BODY_TYPE PLUMBING
J 0
(-3200 2800);
DISPLAY 1.234043 (-3200 2800);
PAINT GREEN (-3200 2800);
DISPLAY INVISIBLE (-3200 2800);
FORCEPROP 1 LAST HDL_TAP TRUE
J 0
(-2875 2725);
DISPLAY 1.234043 (-2875 2725);
PAINT GREEN (-2875 2725);
DISPLAY INVISIBLE (-2875 2725);
FORCEPROP 1 LAST PATH I155
J 0
(-3200 2850);
DISPLAY 0.936170 (-3200 2850);
PAINT GREEN (-3200 2850);
DISPLAY INVISIBLE (-3200 2850);
FORCEADD TAP..6
(-3200 2800);
FORCEPROP 3 LASTPIN (-3150 2800) SIG_NAME M_B_CKE<0>
J 0
(-3140 2810);
DISPLAY 0.659574 (-3140 2810);
PAINT MONO (-3140 2810);
DISPLAY INVISIBLE (-3140 2810);
FORCEPROP 1 LASTPIN (-3150 2800) BN 0
J 0
(-3200 2810);
DISPLAY 0.617021 (-3200 2810);
PAINT PINK (-3200 2810);
FORCEPROP 2 LAST CDS_LIB mstr_standard
J 0
(-3200 2800);
DISPLAY 0.787234 (-3200 2800);
PAINT MONO (-3200 2800);
DISPLAY INVISIBLE (-3200 2800);
FORCEPROP 1 LAST BODY_TYPE PLUMBING
J 0
(-3200 2750);
DISPLAY 1.234043 (-3200 2750);
PAINT GREEN (-3200 2750);
DISPLAY INVISIBLE (-3200 2750);
FORCEPROP 1 LAST HDL_TAP TRUE
J 0
(-2875 2675);
DISPLAY 1.234043 (-2875 2675);
PAINT GREEN (-2875 2675);
DISPLAY INVISIBLE (-2875 2675);
FORCEPROP 1 LAST PATH I156
J 0
(-3200 2800);
DISPLAY 0.936170 (-3200 2800);
PAINT GREEN (-3200 2800);
DISPLAY INVISIBLE (-3200 2800);
FORCEADD OFFPAGE..1
(-3850 2950);
FORCEPROP 2 LAST $XR1 46 
J 0
(-4191 2950);
DISPLAY 0.638298 (-4191 2950);
PAINT MONO (-4191 2950);
FORCEPROP 2 LAST $XR0 24 
J 0
(-4101 2950);
DISPLAY 0.638298 (-4101 2950);
PAINT MONO (-4101 2950);
FORCEPROP 2 LAST CDS_LIB mstr_standard
J 0
(-3850 2950);
DISPLAY 0.787234 (-3850 2950);
PAINT MONO (-3850 2950);
DISPLAY INVISIBLE (-3850 2950);
FORCEPROP 1 LAST OFFPAGE TRUE
J 0
(-3525 2825);
DISPLAY 0.936170 (-3525 2825);
PAINT GREEN (-3525 2825);
DISPLAY INVISIBLE (-3525 2825);
FORCEPROP 1 LAST COMMENT_BODY TRUE
J 0
(-3725 2850);
DISPLAY 0.936170 (-3725 2850);
PAINT GREEN (-3725 2850);
DISPLAY INVISIBLE (-3725 2850);
FORCEPROP 2 LAST PATH I157
J 0
(-3800 3025);
DISPLAY 0.787234 (-3800 3025);
PAINT MONO (-3800 3025);
DISPLAY INVISIBLE (-3800 3025);
FORCEADD TAP..6
(-3200 3100);
FORCEPROP 3 LASTPIN (-3150 3100) SIG_NAME M_B_CS_N<3>
J 0
(-3140 3110);
DISPLAY 0.659574 (-3140 3110);
PAINT MONO (-3140 3110);
DISPLAY INVISIBLE (-3140 3110);
FORCEPROP 1 LASTPIN (-3150 3100) BN 3
J 0
(-3200 3110);
DISPLAY 0.617021 (-3200 3110);
PAINT PINK (-3200 3110);
FORCEPROP 2 LAST CDS_LIB mstr_standard
J 0
(-3200 3100);
DISPLAY 0.787234 (-3200 3100);
PAINT MONO (-3200 3100);
DISPLAY INVISIBLE (-3200 3100);
FORCEPROP 1 LAST BODY_TYPE PLUMBING
J 0
(-3200 3050);
DISPLAY 1.234043 (-3200 3050);
PAINT GREEN (-3200 3050);
DISPLAY INVISIBLE (-3200 3050);
FORCEPROP 1 LAST HDL_TAP TRUE
J 0
(-2875 2975);
DISPLAY 1.234043 (-2875 2975);
PAINT GREEN (-2875 2975);
DISPLAY INVISIBLE (-2875 2975);
FORCEPROP 1 LAST PATH I158
J 0
(-3200 3100);
DISPLAY 0.936170 (-3200 3100);
PAINT GREEN (-3200 3100);
DISPLAY INVISIBLE (-3200 3100);
FORCEADD OFFPAGE..1
(-3850 3150);
FORCEPROP 2 LAST $XR1 46 
J 0
(-4191 3150);
DISPLAY 0.638298 (-4191 3150);
PAINT MONO (-4191 3150);
FORCEPROP 2 LAST $XR0 24 
J 0
(-4101 3150);
DISPLAY 0.638298 (-4101 3150);
PAINT MONO (-4101 3150);
FORCEPROP 2 LAST CDS_LIB mstr_standard
J 0
(-3850 3150);
DISPLAY 0.787234 (-3850 3150);
PAINT MONO (-3850 3150);
DISPLAY INVISIBLE (-3850 3150);
FORCEPROP 1 LAST OFFPAGE TRUE
J 0
(-3525 3025);
DISPLAY 0.936170 (-3525 3025);
PAINT GREEN (-3525 3025);
DISPLAY INVISIBLE (-3525 3025);
FORCEPROP 1 LAST COMMENT_BODY TRUE
J 0
(-3725 3050);
DISPLAY 0.936170 (-3725 3050);
PAINT GREEN (-3725 3050);
DISPLAY INVISIBLE (-3725 3050);
FORCEPROP 2 LAST PATH I159
J 0
(-3800 3225);
DISPLAY 0.787234 (-3800 3225);
PAINT MONO (-3800 3225);
DISPLAY INVISIBLE (-3800 3225);
FORCEADD TAP..6
R 2
(700 4750);
FORCEPROP 3 LASTPIN (650 4750) SIG_NAME M_B_DQS_DP<13>
J 0
(660 4760);
DISPLAY 0.659574 (660 4760);
PAINT MONO (660 4760);
DISPLAY INVISIBLE (660 4760);
FORCEPROP 1 LASTPIN (650 4750) BN 13
J 2
(700 4760);
DISPLAY 0.617021 (700 4760);
PAINT PINK (700 4760);
FORCEPROP 2 LAST CDS_LIB mstr_standard
J 0
(700 4750);
DISPLAY 0.787234 (700 4750);
PAINT MONO (700 4750);
DISPLAY INVISIBLE (700 4750);
FORCEPROP 1 LAST BODY_TYPE PLUMBING
J 2
(700 4700);
DISPLAY 1.234043 (700 4700);
PAINT GREEN (700 4700);
DISPLAY INVISIBLE (700 4700);
FORCEPROP 1 LAST HDL_TAP TRUE
J 2
(375 4625);
DISPLAY 1.234043 (375 4625);
PAINT GREEN (375 4625);
DISPLAY INVISIBLE (375 4625);
FORCEPROP 1 LAST PATH I16
J 2
(700 4750);
DISPLAY 0.936170 (700 4750);
PAINT GREEN (700 4750);
DISPLAY INVISIBLE (700 4750);
FORCEADD TAP..6
(-3200 3050);
FORCEPROP 3 LASTPIN (-3150 3050) SIG_NAME M_B_CS_N<2>
J 0
(-3140 3060);
DISPLAY 0.659574 (-3140 3060);
PAINT MONO (-3140 3060);
DISPLAY INVISIBLE (-3140 3060);
FORCEPROP 1 LASTPIN (-3150 3050) BN 2
J 0
(-3200 3060);
DISPLAY 0.617021 (-3200 3060);
PAINT PINK (-3200 3060);
FORCEPROP 2 LAST CDS_LIB mstr_standard
J 0
(-3200 3050);
DISPLAY 0.787234 (-3200 3050);
PAINT MONO (-3200 3050);
DISPLAY INVISIBLE (-3200 3050);
FORCEPROP 1 LAST BODY_TYPE PLUMBING
J 0
(-3200 3000);
DISPLAY 1.234043 (-3200 3000);
PAINT GREEN (-3200 3000);
DISPLAY INVISIBLE (-3200 3000);
FORCEPROP 1 LAST HDL_TAP TRUE
J 0
(-2875 2925);
DISPLAY 1.234043 (-2875 2925);
PAINT GREEN (-2875 2925);
DISPLAY INVISIBLE (-2875 2925);
FORCEPROP 1 LAST PATH I160
J 0
(-3200 3050);
DISPLAY 0.936170 (-3200 3050);
PAINT GREEN (-3200 3050);
DISPLAY INVISIBLE (-3200 3050);
FORCEADD TAP..6
(-3200 3000);
FORCEPROP 3 LASTPIN (-3150 3000) SIG_NAME M_B_CS_N<1>
J 0
(-3140 3010);
DISPLAY 0.659574 (-3140 3010);
PAINT MONO (-3140 3010);
DISPLAY INVISIBLE (-3140 3010);
FORCEPROP 1 LASTPIN (-3150 3000) BN 1
J 0
(-3200 3010);
DISPLAY 0.617021 (-3200 3010);
PAINT PINK (-3200 3010);
FORCEPROP 2 LAST CDS_LIB mstr_standard
J 0
(-3200 3000);
DISPLAY 0.787234 (-3200 3000);
PAINT MONO (-3200 3000);
DISPLAY INVISIBLE (-3200 3000);
FORCEPROP 1 LAST BODY_TYPE PLUMBING
J 0
(-3200 2950);
DISPLAY 1.234043 (-3200 2950);
PAINT GREEN (-3200 2950);
DISPLAY INVISIBLE (-3200 2950);
FORCEPROP 1 LAST HDL_TAP TRUE
J 0
(-2875 2875);
DISPLAY 1.234043 (-2875 2875);
PAINT GREEN (-2875 2875);
DISPLAY INVISIBLE (-2875 2875);
FORCEPROP 1 LAST PATH I161
J 0
(-3200 3000);
DISPLAY 0.936170 (-3200 3000);
PAINT GREEN (-3200 3000);
DISPLAY INVISIBLE (-3200 3000);
FORCEADD TAP..6
(-3200 2950);
FORCEPROP 3 LASTPIN (-3150 2950) SIG_NAME M_B_CS_N<0>
J 0
(-3140 2960);
DISPLAY 0.659574 (-3140 2960);
PAINT MONO (-3140 2960);
DISPLAY INVISIBLE (-3140 2960);
FORCEPROP 1 LASTPIN (-3150 2950) BN 0
J 0
(-3200 2960);
DISPLAY 0.617021 (-3200 2960);
PAINT PINK (-3200 2960);
FORCEPROP 2 LAST CDS_LIB mstr_standard
J 0
(-3200 2950);
DISPLAY 0.787234 (-3200 2950);
PAINT MONO (-3200 2950);
DISPLAY INVISIBLE (-3200 2950);
FORCEPROP 1 LAST BODY_TYPE PLUMBING
J 0
(-3200 2900);
DISPLAY 1.234043 (-3200 2900);
PAINT GREEN (-3200 2900);
DISPLAY INVISIBLE (-3200 2900);
FORCEPROP 1 LAST HDL_TAP TRUE
J 0
(-2875 2825);
DISPLAY 1.234043 (-2875 2825);
PAINT GREEN (-2875 2825);
DISPLAY INVISIBLE (-2875 2825);
FORCEPROP 1 LAST PATH I162
J 0
(-3200 2950);
DISPLAY 0.936170 (-3200 2950);
PAINT GREEN (-3200 2950);
DISPLAY INVISIBLE (-3200 2950);
FORCEADD TAP..6
(-3400 3350);
FORCEPROP 3 LASTPIN (-3350 3350) SIG_NAME M_B_CLK_DN<1>
J 0
(-3340 3360);
DISPLAY 0.659574 (-3340 3360);
PAINT MONO (-3340 3360);
DISPLAY INVISIBLE (-3340 3360);
FORCEPROP 1 LASTPIN (-3350 3350) BN 1
J 0
(-3400 3360);
DISPLAY 0.617021 (-3400 3360);
PAINT PINK (-3400 3360);
FORCEPROP 2 LAST CDS_LIB mstr_standard
J 0
(-3400 3350);
DISPLAY 0.787234 (-3400 3350);
PAINT MONO (-3400 3350);
DISPLAY INVISIBLE (-3400 3350);
FORCEPROP 1 LAST BODY_TYPE PLUMBING
J 0
(-3400 3300);
DISPLAY 1.234043 (-3400 3300);
PAINT GREEN (-3400 3300);
DISPLAY INVISIBLE (-3400 3300);
FORCEPROP 1 LAST HDL_TAP TRUE
J 0
(-3075 3225);
DISPLAY 1.234043 (-3075 3225);
PAINT GREEN (-3075 3225);
DISPLAY INVISIBLE (-3075 3225);
FORCEPROP 1 LAST PATH I163
J 0
(-3400 3350);
DISPLAY 0.936170 (-3400 3350);
PAINT GREEN (-3400 3350);
DISPLAY INVISIBLE (-3400 3350);
FORCEADD TAP..6
(-3400 3250);
FORCEPROP 3 LASTPIN (-3350 3250) SIG_NAME M_B_CLK_DN<0>
J 0
(-3340 3260);
DISPLAY 0.659574 (-3340 3260);
PAINT MONO (-3340 3260);
DISPLAY INVISIBLE (-3340 3260);
FORCEPROP 1 LASTPIN (-3350 3250) BN 0
J 0
(-3400 3260);
DISPLAY 0.617021 (-3400 3260);
PAINT PINK (-3400 3260);
FORCEPROP 2 LAST CDS_LIB mstr_standard
J 0
(-3400 3250);
DISPLAY 0.787234 (-3400 3250);
PAINT MONO (-3400 3250);
DISPLAY INVISIBLE (-3400 3250);
FORCEPROP 1 LAST BODY_TYPE PLUMBING
J 0
(-3400 3200);
DISPLAY 1.234043 (-3400 3200);
PAINT GREEN (-3400 3200);
DISPLAY INVISIBLE (-3400 3200);
FORCEPROP 1 LAST HDL_TAP TRUE
J 0
(-3075 3125);
DISPLAY 1.234043 (-3075 3125);
PAINT GREEN (-3075 3125);
DISPLAY INVISIBLE (-3075 3125);
FORCEPROP 1 LAST PATH I164
J 0
(-3400 3250);
DISPLAY 0.936170 (-3400 3250);
PAINT GREEN (-3400 3250);
DISPLAY INVISIBLE (-3400 3250);
FORCEADD TAP..6
(-3200 3300);
FORCEPROP 3 LASTPIN (-3150 3300) SIG_NAME M_B_CLK_DP<0>
J 0
(-3140 3310);
DISPLAY 0.659574 (-3140 3310);
PAINT MONO (-3140 3310);
DISPLAY INVISIBLE (-3140 3310);
FORCEPROP 1 LASTPIN (-3150 3300) BN 0
J 0
(-3200 3310);
DISPLAY 0.617021 (-3200 3310);
PAINT PINK (-3200 3310);
FORCEPROP 2 LAST CDS_LIB mstr_standard
J 0
(-3200 3300);
DISPLAY 0.787234 (-3200 3300);
PAINT MONO (-3200 3300);
DISPLAY INVISIBLE (-3200 3300);
FORCEPROP 1 LAST BODY_TYPE PLUMBING
J 0
(-3200 3250);
DISPLAY 1.234043 (-3200 3250);
PAINT GREEN (-3200 3250);
DISPLAY INVISIBLE (-3200 3250);
FORCEPROP 1 LAST HDL_TAP TRUE
J 0
(-2875 3175);
DISPLAY 1.234043 (-2875 3175);
PAINT GREEN (-2875 3175);
DISPLAY INVISIBLE (-2875 3175);
FORCEPROP 1 LAST PATH I165
J 0
(-3200 3300);
DISPLAY 0.936170 (-3200 3300);
PAINT GREEN (-3200 3300);
DISPLAY INVISIBLE (-3200 3300);
FORCEADD TAP..6
(-3200 3400);
FORCEPROP 3 LASTPIN (-3150 3400) SIG_NAME M_B_CLK_DP<1>
J 0
(-3140 3410);
DISPLAY 0.659574 (-3140 3410);
PAINT MONO (-3140 3410);
DISPLAY INVISIBLE (-3140 3410);
FORCEPROP 1 LASTPIN (-3150 3400) BN 1
J 0
(-3200 3410);
DISPLAY 0.617021 (-3200 3410);
PAINT PINK (-3200 3410);
FORCEPROP 2 LAST CDS_LIB mstr_standard
J 0
(-3200 3400);
DISPLAY 0.787234 (-3200 3400);
PAINT MONO (-3200 3400);
DISPLAY INVISIBLE (-3200 3400);
FORCEPROP 1 LAST BODY_TYPE PLUMBING
J 0
(-3200 3350);
DISPLAY 1.234043 (-3200 3350);
PAINT GREEN (-3200 3350);
DISPLAY INVISIBLE (-3200 3350);
FORCEPROP 1 LAST HDL_TAP TRUE
J 0
(-2875 3275);
DISPLAY 1.234043 (-2875 3275);
PAINT GREEN (-2875 3275);
DISPLAY INVISIBLE (-2875 3275);
FORCEPROP 1 LAST PATH I166
J 0
(-3200 3400);
DISPLAY 0.936170 (-3200 3400);
PAINT GREEN (-3200 3400);
DISPLAY INVISIBLE (-3200 3400);
FORCEADD OFFPAGE..1
(-4000 3450);
FORCEPROP 2 LAST $XR1 46 
J 0
(-4341 3450);
DISPLAY 0.638298 (-4341 3450);
PAINT MONO (-4341 3450);
FORCEPROP 2 LAST $XR0 24 
J 0
(-4251 3450);
DISPLAY 0.638298 (-4251 3450);
PAINT MONO (-4251 3450);
FORCEPROP 2 LAST CDS_LIB mstr_standard
J 0
(-4000 3450);
DISPLAY 0.787234 (-4000 3450);
PAINT MONO (-4000 3450);
DISPLAY INVISIBLE (-4000 3450);
FORCEPROP 1 LAST OFFPAGE TRUE
J 0
(-3675 3325);
DISPLAY 0.936170 (-3675 3325);
PAINT GREEN (-3675 3325);
DISPLAY INVISIBLE (-3675 3325);
FORCEPROP 1 LAST COMMENT_BODY TRUE
J 0
(-3875 3350);
DISPLAY 0.936170 (-3875 3350);
PAINT GREEN (-3875 3350);
DISPLAY INVISIBLE (-3875 3350);
FORCEPROP 2 LAST PATH I167
J 0
(-3950 3525);
DISPLAY 0.787234 (-3950 3525);
PAINT MONO (-3950 3525);
DISPLAY INVISIBLE (-3950 3525);
FORCEADD OFFPAGE..1
(-4000 3500);
FORCEPROP 2 LAST $XR1 46 
J 0
(-4341 3500);
DISPLAY 0.638298 (-4341 3500);
PAINT MONO (-4341 3500);
FORCEPROP 2 LAST $XR0 24 
J 0
(-4251 3500);
DISPLAY 0.638298 (-4251 3500);
PAINT MONO (-4251 3500);
FORCEPROP 2 LAST CDS_LIB mstr_standard
J 0
(-4000 3500);
DISPLAY 0.787234 (-4000 3500);
PAINT MONO (-4000 3500);
DISPLAY INVISIBLE (-4000 3500);
FORCEPROP 1 LAST OFFPAGE TRUE
J 0
(-3675 3375);
DISPLAY 0.936170 (-3675 3375);
PAINT GREEN (-3675 3375);
DISPLAY INVISIBLE (-3675 3375);
FORCEPROP 1 LAST COMMENT_BODY TRUE
J 0
(-3875 3400);
DISPLAY 0.936170 (-3875 3400);
PAINT GREEN (-3875 3400);
DISPLAY INVISIBLE (-3875 3400);
FORCEPROP 2 LAST PATH I168
J 0
(-3950 3575);
DISPLAY 0.787234 (-3950 3575);
PAINT MONO (-3950 3575);
DISPLAY INVISIBLE (-3950 3575);
FORCEADD SCONN288_H44441004..4
(50 2000);
FORCEPROP 1 LAST LOCATION J4G2
J 0
(-400 3100);
DISPLAY 0.617021 (-400 3100);
PAINT AQUA (-400 3100);
FORCEPROP 1 LAST PART_NUMBER H44441-004
J 0
(-400 950);
DISPLAY 0.617021 (-400 950);
PAINT BLUE (-400 950);
FORCEPROP 1 LAST MATERIAL SCONN
J 0
(-400 3050);
DISPLAY 0.617021 (-400 3050);
PAINT SKYBLUE (-400 3050);
FORCEPROP 2 LASTPIN (-450 2550) $PN 77
J 2
(-460 2560);
DISPLAY 0.617021 (-460 2560);
PAINT ORANGE (-460 2560);
FORCEPROP 2 LASTPIN (-450 2500) $PN 221
J 2
(-460 2510);
DISPLAY 0.617021 (-460 2510);
PAINT ORANGE (-460 2510);
FORCEPROP 2 LASTPIN (-450 2850) $PN 142
J 2
(-460 2860);
DISPLAY 0.617021 (-460 2860);
PAINT ORANGE (-460 2860);
FORCEPROP 2 LASTPIN (-450 2800) $PN 143
J 2
(-460 2810);
DISPLAY 0.617021 (-460 2810);
PAINT ORANGE (-460 2810);
FORCEPROP 2 LASTPIN (-450 2750) $PN 288
J 2
(-460 2760);
DISPLAY 0.617021 (-460 2760);
PAINT ORANGE (-460 2760);
FORCEPROP 2 LASTPIN (-450 2700) $PN 286
J 2
(-460 2710);
DISPLAY 0.617021 (-460 2710);
PAINT ORANGE (-460 2710);
FORCEPROP 2 LASTPIN (-450 2650) $PN 287
J 2
(-460 2660);
DISPLAY 0.617021 (-460 2660);
PAINT ORANGE (-460 2660);
FORCEPROP 2 LASTPIN (-450 2400) $PN 59
J 2
(-460 2410);
DISPLAY 0.617021 (-460 2410);
PAINT ORANGE (-460 2410);
FORCEPROP 2 LASTPIN (-450 2350) $PN 61
J 2
(-460 2360);
DISPLAY 0.617021 (-460 2360);
PAINT ORANGE (-460 2360);
FORCEPROP 2 LASTPIN (-450 2300) $PN 64
J 2
(-460 2310);
DISPLAY 0.617021 (-460 2310);
PAINT ORANGE (-460 2310);
FORCEPROP 2 LASTPIN (-450 2250) $PN 67
J 2
(-460 2260);
DISPLAY 0.617021 (-460 2260);
PAINT ORANGE (-460 2260);
FORCEPROP 2 LASTPIN (-450 2200) $PN 70
J 2
(-460 2210);
DISPLAY 0.617021 (-460 2210);
PAINT ORANGE (-460 2210);
FORCEPROP 2 LASTPIN (-450 2150) $PN 73
J 2
(-460 2160);
DISPLAY 0.617021 (-460 2160);
PAINT ORANGE (-460 2160);
FORCEPROP 2 LASTPIN (-450 2100) $PN 76
J 2
(-460 2110);
DISPLAY 0.617021 (-460 2110);
PAINT ORANGE (-460 2110);
FORCEPROP 2 LASTPIN (-450 2050) $PN 80
J 2
(-460 2060);
DISPLAY 0.617021 (-460 2060);
PAINT ORANGE (-460 2060);
FORCEPROP 2 LASTPIN (-450 2000) $PN 83
J 2
(-460 2010);
DISPLAY 0.617021 (-460 2010);
PAINT ORANGE (-460 2010);
FORCEPROP 2 LASTPIN (-450 1950) $PN 85
J 2
(-460 1960);
DISPLAY 0.617021 (-460 1960);
PAINT ORANGE (-460 1960);
FORCEPROP 2 LASTPIN (-450 1900) $PN 88
J 2
(-460 1910);
DISPLAY 0.617021 (-460 1910);
PAINT ORANGE (-460 1910);
FORCEPROP 2 LASTPIN (-450 1850) $PN 90
J 2
(-460 1860);
DISPLAY 0.617021 (-460 1860);
PAINT ORANGE (-460 1860);
FORCEPROP 2 LASTPIN (-450 1800) $PN 92
J 2
(-460 1810);
DISPLAY 0.617021 (-460 1810);
PAINT ORANGE (-460 1810);
FORCEPROP 2 LASTPIN (-450 1750) $PN 204
J 2
(-460 1760);
DISPLAY 0.617021 (-460 1760);
PAINT ORANGE (-460 1760);
FORCEPROP 2 LASTPIN (-450 1700) $PN 206
J 2
(-460 1710);
DISPLAY 0.617021 (-460 1710);
PAINT ORANGE (-460 1710);
FORCEPROP 2 LASTPIN (-450 1650) $PN 209
J 2
(-460 1660);
DISPLAY 0.617021 (-460 1660);
PAINT ORANGE (-460 1660);
FORCEPROP 2 LASTPIN (-450 1600) $PN 212
J 2
(-460 1610);
DISPLAY 0.617021 (-460 1610);
PAINT ORANGE (-460 1610);
FORCEPROP 2 LASTPIN (-450 1550) $PN 215
J 2
(-460 1560);
DISPLAY 0.617021 (-460 1560);
PAINT ORANGE (-460 1560);
FORCEPROP 2 LASTPIN (-450 1500) $PN 217
J 2
(-460 1510);
DISPLAY 0.617021 (-460 1510);
PAINT ORANGE (-460 1510);
FORCEPROP 2 LASTPIN (-450 1450) $PN 220
J 2
(-460 1460);
DISPLAY 0.617021 (-460 1460);
PAINT ORANGE (-460 1460);
FORCEPROP 2 LASTPIN (-450 1400) $PN 223
J 2
(-460 1410);
DISPLAY 0.617021 (-460 1410);
PAINT ORANGE (-460 1410);
FORCEPROP 2 LASTPIN (-450 1350) $PN 226
J 2
(-460 1360);
DISPLAY 0.617021 (-460 1360);
PAINT ORANGE (-460 1360);
FORCEPROP 2 LASTPIN (-450 1300) $PN 229
J 2
(-460 1310);
DISPLAY 0.617021 (-460 1310);
PAINT ORANGE (-460 1310);
FORCEPROP 2 LASTPIN (-450 1250) $PN 231
J 2
(-460 1260);
DISPLAY 0.617021 (-460 1260);
PAINT ORANGE (-460 1260);
FORCEPROP 2 LASTPIN (-450 1200) $PN 233
J 2
(-460 1210);
DISPLAY 0.617021 (-460 1210);
PAINT ORANGE (-460 1210);
FORCEPROP 2 LASTPIN (-450 1150) $PN 236
J 2
(-460 1160);
DISPLAY 0.617021 (-460 1160);
PAINT ORANGE (-460 1160);
FORCEPROP 2 LASTPIN (550 2850) $PN 1
J 0
(560 2860);
DISPLAY 0.617021 (560 2860);
PAINT ORANGE (560 2860);
FORCEPROP 2 LASTPIN (550 2800) $PN 145
J 0
(560 2810);
DISPLAY 0.617021 (560 2810);
PAINT ORANGE (560 2810);
FORCEPROP 1 LAST PACK_TYPE PIP
J 0
(-400 3150);
PAINT SKYBLUE (-400 3150);
DISPLAY INVISIBLE (-400 3150);
FORCEPROP 2 LAST BOM_COST MEM
J 0
(50 2000);
PAINT ORANGE (50 2000);
DISPLAY INVISIBLE (50 2000);
FORCEPROP 2 LAST CDS_LIB mstr_sconn
J 0
(50 2000);
PAINT ORANGE (50 2000);
DISPLAY INVISIBLE (50 2000);
FORCEPROP 2 LAST SEC_TYPE PIP
J 0
(-400 3150);
DISPLAY 1.021277 (-400 3150);
PAINT ORANGE (-400 3150);
DISPLAY INVISIBLE (-400 3150);
FORCEPROP 2 LAST SEC 4
J 0
(-400 3150);
DISPLAY 0.680851 (-400 3150);
PAINT MONO (-400 3150);
DISPLAY INVISIBLE (-400 3150);
FORCEPROP 2 LAST CDS_LOCATION J4G2
J 0
(-400 3100);
DISPLAY 0.617021 (-400 3100);
PAINT AQUA (-400 3100);
DISPLAY INVISIBLE (-400 3100);
FORCEPROP 1 LAST PATH I169
J 0
(50 3050);
PAINT GREEN (50 3050);
DISPLAY INVISIBLE (50 3050);
FORCEPROP 2 LAST ROOM DDR4_CH_B
J 0
(50 2000);
PAINT ORANGE (50 2000);
DISPLAY INVISIBLE (50 2000);
FORCEADD TAP..6
R 2
(700 4650);
FORCEPROP 3 LASTPIN (650 4650) SIG_NAME M_B_DQS_DP<12>
J 0
(660 4660);
DISPLAY 0.659574 (660 4660);
PAINT MONO (660 4660);
DISPLAY INVISIBLE (660 4660);
FORCEPROP 1 LASTPIN (650 4650) BN 12
J 2
(700 4660);
DISPLAY 0.617021 (700 4660);
PAINT PINK (700 4660);
FORCEPROP 2 LAST CDS_LIB mstr_standard
J 0
(700 4650);
DISPLAY 0.787234 (700 4650);
PAINT MONO (700 4650);
DISPLAY INVISIBLE (700 4650);
FORCEPROP 1 LAST BODY_TYPE PLUMBING
J 2
(700 4600);
DISPLAY 1.234043 (700 4600);
PAINT GREEN (700 4600);
DISPLAY INVISIBLE (700 4600);
FORCEPROP 1 LAST HDL_TAP TRUE
J 2
(375 4525);
DISPLAY 1.234043 (375 4525);
PAINT GREEN (375 4525);
DISPLAY INVISIBLE (375 4525);
FORCEPROP 1 LAST PATH I17
J 2
(700 4650);
DISPLAY 0.936170 (700 4650);
PAINT GREEN (700 4650);
DISPLAY INVISIBLE (700 4650);
FORCEADD GND..1
R 2
(-5050 1600);
FORCEPROP 3 LASTPIN (-5050 1650) SIG_NAME GND\g
J 0
(-5040 1660);
DISPLAY 0.659574 (-5040 1660);
PAINT MONO (-5040 1660);
DISPLAY INVISIBLE (-5040 1660);
FORCEPROP 1 LAST VOLTAGE 0
J 0
(-5050 1600);
PAINT SKYBLUE (-5050 1600);
DISPLAY INVISIBLE (-5050 1600);
FORCEPROP 2 LAST BOM_COST MEM
J 0
(-5050 1605);
PAINT ORANGE (-5050 1605);
DISPLAY INVISIBLE (-5050 1605);
FORCEPROP 2 LAST CDS_LIB mstr_symbols
J 0
(-5050 1600);
DISPLAY 0.787234 (-5050 1600);
PAINT MONO (-5050 1600);
DISPLAY INVISIBLE (-5050 1600);
FORCEPROP 1 LAST SIZE 1B
J 2
(-5125 1550);
DISPLAY 1.170213 (-5125 1550);
PAINT GREEN (-5125 1550);
DISPLAY INVISIBLE (-5125 1550);
FORCEPROP 1 LAST BODY_TYPE PLUMBING
J 2
(-5005 1557);
DISPLAY 0.340426 (-5005 1557);
PAINT GREEN (-5005 1557);
DISPLAY INVISIBLE (-5005 1557);
FORCEPROP 1 LAST PATH I174
J 2
(-5125 1600);
DISPLAY 1.404255 (-5125 1600);
PAINT GREEN (-5125 1600);
DISPLAY INVISIBLE (-5125 1600);
FORCEPROP 2 LAST ROOM DDR4_CH_A
J 0
(-5050 1605);
PAINT ORANGE (-5050 1605);
DISPLAY INVISIBLE (-5050 1605);
FORCEPROP 1 LAST HDL_POWER GND
J 2
(-5050 1750);
DISPLAY 0.553191 (-5050 1750);
PAINT GREEN (-5050 1750);
DISPLAY INVISIBLE (-5050 1750);
FORCEADD OFFPAGE..6
(-3850 1600);
FORCEPROP 2 LASTPIN (-3800 1600) SIG_NAME SMB_DDR_ABC_VPP_SDA
J 0
(-3760 1610);
DISPLAY 0.617021 (-3760 1610);
PAINT ORANGE (-3760 1610);
FORCEPROP 2 LAST $XR5 99 
J 0
(-4549 1600);
DISPLAY 0.638298 (-4549 1600);
PAINT MONO (-4549 1600);
FORCEPROP 2 LAST $XR4 48 
J 0
(-4459 1600);
DISPLAY 0.638298 (-4459 1600);
PAINT MONO (-4459 1600);
FORCEPROP 2 LAST $XR3 47 
J 0
(-4369 1600);
DISPLAY 0.638298 (-4369 1600);
PAINT MONO (-4369 1600);
FORCEPROP 2 LAST $XR2 46 
J 0
(-4279 1600);
DISPLAY 0.638298 (-4279 1600);
PAINT MONO (-4279 1600);
FORCEPROP 2 LAST $XR1 44 
J 0
(-4189 1600);
DISPLAY 0.638298 (-4189 1600);
PAINT MONO (-4189 1600);
FORCEPROP 2 LAST $XR0 43 
J 0
(-4099 1600);
DISPLAY 0.638298 (-4099 1600);
PAINT MONO (-4099 1600);
FORCEPROP 2 LAST CDS_LIB mstr_standard
J 0
(-3850 1600);
DISPLAY 0.787234 (-3850 1600);
PAINT MONO (-3850 1600);
DISPLAY INVISIBLE (-3850 1600);
FORCEPROP 1 LAST OFFPAGE TRUE
J 0
(-3525 1475);
DISPLAY 0.936170 (-3525 1475);
PAINT GREEN (-3525 1475);
DISPLAY INVISIBLE (-3525 1475);
FORCEPROP 1 LAST COMMENT_BODY TRUE
J 0
(-3750 1525);
DISPLAY 0.936170 (-3750 1525);
PAINT GREEN (-3750 1525);
DISPLAY INVISIBLE (-3750 1525);
FORCEPROP 2 LAST PATH I175
J 0
(-4150 1650);
DISPLAY 0.787234 (-4150 1650);
PAINT ORANGE (-4150 1650);
DISPLAY INVISIBLE (-4150 1650);
FORCEADD OFFPAGE..1
(-3850 1550);
FORCEPROP 2 LAST $XR5 48 
J 0
(-4551 1550);
DISPLAY 0.638298 (-4551 1550);
PAINT MONO (-4551 1550);
FORCEPROP 2 LAST $XR4 47 
J 0
(-4461 1550);
DISPLAY 0.638298 (-4461 1550);
PAINT MONO (-4461 1550);
FORCEPROP 2 LAST $XR3 46 
J 0
(-4371 1550);
DISPLAY 0.638298 (-4371 1550);
PAINT MONO (-4371 1550);
FORCEPROP 2 LAST $XR2 44 
J 0
(-4281 1550);
DISPLAY 0.638298 (-4281 1550);
PAINT MONO (-4281 1550);
FORCEPROP 2 LAST $XR1 43 
J 0
(-4191 1550);
DISPLAY 0.638298 (-4191 1550);
PAINT MONO (-4191 1550);
FORCEPROP 2 LAST $XR0 99 
J 0
(-4101 1550);
DISPLAY 0.638298 (-4101 1550);
PAINT MONO (-4101 1550);
FORCEPROP 2 LAST CDS_LIB mstr_standard
J 0
(-3850 1550);
DISPLAY 0.787234 (-3850 1550);
PAINT MONO (-3850 1550);
DISPLAY INVISIBLE (-3850 1550);
FORCEPROP 1 LAST OFFPAGE TRUE
J 0
(-3525 1425);
DISPLAY 0.936170 (-3525 1425);
PAINT GREEN (-3525 1425);
DISPLAY INVISIBLE (-3525 1425);
FORCEPROP 1 LAST COMMENT_BODY TRUE
J 0
(-3725 1450);
DISPLAY 0.936170 (-3725 1450);
PAINT GREEN (-3725 1450);
DISPLAY INVISIBLE (-3725 1450);
FORCEPROP 2 LAST PATH I176
J 0
(-4125 1600);
DISPLAY 0.787234 (-4125 1600);
PAINT ORANGE (-4125 1600);
DISPLAY INVISIBLE (-4125 1600);
FORCEADD OFFPAGE..5
(-4175 2300);
FORCEPROP 2 LAST $XR23 94 
J 0
(-4789 2336);
DISPLAY 0.638298 (-4789 2336);
PAINT MONO (-4789 2336);
FORCEPROP 2 LAST $XR22 88 
J 0
(-4699 2336);
DISPLAY 0.638298 (-4699 2336);
PAINT MONO (-4699 2336);
FORCEPROP 2 LAST $XR21 87 
J 0
(-4609 2336);
DISPLAY 0.638298 (-4609 2336);
PAINT MONO (-4609 2336);
FORCEPROP 2 LAST $XR20 86 
J 0
(-4519 2336);
DISPLAY 0.638298 (-4519 2336);
PAINT MONO (-4519 2336);
FORCEPROP 2 LAST $XR19 85 
J 0
(-4429 2336);
DISPLAY 0.638298 (-4429 2336);
PAINT MONO (-4429 2336);
FORCEPROP 2 LAST $XR18 84 
J 0
(-5149 2264);
DISPLAY 0.638298 (-5149 2264);
PAINT MONO (-5149 2264);
FORCEPROP 2 LAST $XR17 83 
J 0
(-5059 2264);
DISPLAY 0.638298 (-5059 2264);
PAINT MONO (-5059 2264);
FORCEPROP 2 LAST $XR16 82 
J 0
(-4969 2264);
DISPLAY 0.638298 (-4969 2264);
PAINT MONO (-4969 2264);
FORCEPROP 2 LAST $XR15 81 
J 0
(-4879 2264);
DISPLAY 0.638298 (-4879 2264);
PAINT MONO (-4879 2264);
FORCEPROP 2 LAST $XR14 80 
J 0
(-4789 2264);
DISPLAY 0.638298 (-4789 2264);
PAINT MONO (-4789 2264);
FORCEPROP 2 LAST $XR13 79 
J 0
(-4699 2264);
DISPLAY 0.638298 (-4699 2264);
PAINT MONO (-4699 2264);
FORCEPROP 2 LAST $XR12 78 
J 0
(-4609 2264);
DISPLAY 0.638298 (-4609 2264);
PAINT MONO (-4609 2264);
FORCEPROP 2 LAST $XR11 77 
J 0
(-4519 2264);
DISPLAY 0.638298 (-4519 2264);
PAINT MONO (-4519 2264);
FORCEPROP 2 LAST $XR10 54 
J 0
(-4429 2264);
DISPLAY 0.638298 (-4429 2264);
PAINT MONO (-4429 2264);
FORCEPROP 2 LAST $XR9 53 
J 0
(-5239 2300);
DISPLAY 0.638298 (-5239 2300);
PAINT MONO (-5239 2300);
FORCEPROP 2 LAST $XR8 52 
J 0
(-5149 2300);
DISPLAY 0.638298 (-5149 2300);
PAINT MONO (-5149 2300);
FORCEPROP 2 LAST $XR7 51 
J 0
(-5059 2300);
DISPLAY 0.638298 (-5059 2300);
PAINT MONO (-5059 2300);
FORCEPROP 2 LAST $XR6 50 
J 0
(-4969 2300);
DISPLAY 0.638298 (-4969 2300);
PAINT MONO (-4969 2300);
FORCEPROP 2 LAST $XR5 49 
J 0
(-4879 2300);
DISPLAY 0.638298 (-4879 2300);
PAINT MONO (-4879 2300);
FORCEPROP 2 LAST $XR4 48 
J 0
(-4789 2300);
DISPLAY 0.638298 (-4789 2300);
PAINT MONO (-4789 2300);
FORCEPROP 2 LAST $XR3 47 
J 0
(-4699 2300);
DISPLAY 0.638298 (-4699 2300);
PAINT MONO (-4699 2300);
FORCEPROP 2 LAST $XR2 46 
J 0
(-4609 2300);
DISPLAY 0.638298 (-4609 2300);
PAINT MONO (-4609 2300);
FORCEPROP 2 LAST $XR1 44 
J 0
(-4519 2300);
DISPLAY 0.638298 (-4519 2300);
PAINT MONO (-4519 2300);
FORCEPROP 2 LAST $XR0 43 
J 0
(-4429 2300);
DISPLAY 0.638298 (-4429 2300);
PAINT MONO (-4429 2300);
FORCEPROP 2 LAST CDS_LIB mstr_standard
J 0
(-4175 2300);
DISPLAY 0.787234 (-4175 2300);
PAINT MONO (-4175 2300);
DISPLAY INVISIBLE (-4175 2300);
FORCEPROP 1 LAST OFFPAGE TRUE
J 0
(-3850 2175);
DISPLAY 1.404255 (-3850 2175);
PAINT GREEN (-3850 2175);
DISPLAY INVISIBLE (-3850 2175);
FORCEPROP 1 LAST COMMENT_BODY TRUE
J 0
(-4075 2225);
DISPLAY 1.404255 (-4075 2225);
PAINT GREEN (-4075 2225);
DISPLAY INVISIBLE (-4075 2225);
FORCEPROP 2 LAST PATH I177
J 0
(-4450 2350);
PAINT ORANGE (-4450 2350);
DISPLAY INVISIBLE (-4450 2350);
FORCEADD GND..1
(-4600 1000);
FORCEPROP 3 LASTPIN (-4600 1050) SIG_NAME GND\g
J 0
(-4590 1060);
DISPLAY 0.659574 (-4590 1060);
PAINT MONO (-4590 1060);
DISPLAY INVISIBLE (-4590 1060);
FORCEPROP 1 LAST VOLTAGE 0
J 0
(-4600 1000);
PAINT SKYBLUE (-4600 1000);
DISPLAY INVISIBLE (-4600 1000);
FORCEPROP 2 LAST CDS_LIB mstr_symbols
J 0
(-4600 1000);
PAINT ORANGE (-4600 1000);
DISPLAY INVISIBLE (-4600 1000);
FORCEPROP 1 LAST SIZE 1B
J 0
(-4525 950);
DISPLAY 1.787234 (-4525 950);
PAINT GREEN (-4525 950);
DISPLAY INVISIBLE (-4525 950);
FORCEPROP 2 LAST BOM_COST MEM
J 0
(-4600 1005);
PAINT ORANGE (-4600 1005);
DISPLAY INVISIBLE (-4600 1005);
FORCEPROP 1 LAST BODY_TYPE PLUMBING
J 0
(-4645 957);
DISPLAY 0.340426 (-4645 957);
PAINT GREEN (-4645 957);
DISPLAY INVISIBLE (-4645 957);
FORCEPROP 1 LAST PATH I178
J 0
(-4525 1000);
DISPLAY 1.404255 (-4525 1000);
PAINT GREEN (-4525 1000);
DISPLAY INVISIBLE (-4525 1000);
FORCEPROP 2 LAST ROOM DDR4_CH_A
J 0
(-4600 1005);
PAINT ORANGE (-4600 1005);
DISPLAY INVISIBLE (-4600 1005);
FORCEPROP 1 LAST HDL_POWER GND
J 0
(-4600 1150);
DISPLAY 1.404255 (-4600 1150);
PAINT GREEN (-4600 1150);
DISPLAY INVISIBLE (-4600 1150);
FORCEADD CAP_A..1
R 2
(-4600 1250);
FORCEPROP 1 LAST LOCATION C4G3
J 2
(-4650 1350);
DISPLAY 0.617021 (-4650 1350);
PAINT AQUA (-4650 1350);
FORCEPROP 1 LAST PART_NUMBER A36096-045
J 2
(-4650 1100);
DISPLAY 0.617021 (-4650 1100);
PAINT BLUE (-4650 1100);
FORCEPROP 1 LAST VALUE 0.01UF
J 2
(-4650 1300);
DISPLAY 0.617021 (-4650 1300);
PAINT SKYBLUE (-4650 1300);
FORCEPROP 1 LAST TOLERANCE 10%
J 2
(-4650 1200);
DISPLAY 0.617021 (-4650 1200);
PAINT SKYBLUE (-4650 1200);
FORCEPROP 1 LAST VOLTAGE 25V
J 2
(-4650 1250);
DISPLAY 0.617021 (-4650 1250);
PAINT SKYBLUE (-4650 1250);
FORCEPROP 1 LAST MATERIAL X7R
J 2
(-4650 1150);
DISPLAY 0.617021 (-4650 1150);
PAINT SKYBLUE (-4650 1150);
FORCEPROP 1 LAST PACK_TYPE 0402V
J 2
(-4650 1050);
DISPLAY 0.617021 (-4650 1050);
PAINT SKYBLUE (-4650 1050);
FORCEPROP 1 LASTPIN (-4600 1150) $PN 2
J 2
(-4610 1130);
DISPLAY 0.787234 (-4610 1130);
PAINT ORANGE (-4610 1130);
FORCEPROP 1 LASTPIN (-4600 1350) $PN 1
J 2
(-4610 1330);
DISPLAY 0.787234 (-4610 1330);
PAINT ORANGE (-4610 1330);
FORCEPROP 2 LAST CDS_LOCATION C4G3
J 2
(-4650 1350);
DISPLAY 0.617021 (-4650 1350);
PAINT AQUA (-4650 1350);
DISPLAY INVISIBLE (-4650 1350);
FORCEPROP 2 LAST BOM_COST MEM
J 0
(-4600 1250);
PAINT ORANGE (-4600 1250);
DISPLAY INVISIBLE (-4600 1250);
FORCEPROP 2 LAST CDS_LIB dev_discrete
J 0
(-4600 1250);
PAINT ORANGE (-4600 1250);
DISPLAY INVISIBLE (-4600 1250);
FORCEPROP 1 LAST PATH I179
J 2
(-4650 1400);
DISPLAY 0.978723 (-4650 1400);
PAINT WHITE (-4650 1400);
DISPLAY INVISIBLE (-4650 1400);
FORCEPROP 2 LAST ROOM DDR4_CH_A
J 0
(-4600 1250);
PAINT ORANGE (-4600 1250);
DISPLAY INVISIBLE (-4600 1250);
FORCEPROP 2 LAST SEC 1
J 0
(-4650 1450);
PAINT MONO (-4650 1450);
DISPLAY INVISIBLE (-4650 1450);
FORCEPROP 2 LAST SEC_TYPE 0402V
J 0
(-4650 1450);
DISPLAY 1.021277 (-4650 1450);
PAINT ORANGE (-4650 1450);
DISPLAY INVISIBLE (-4650 1450);
FORCEADD TAP..6
R 2
(700 4550);
FORCEPROP 3 LASTPIN (650 4550) SIG_NAME M_B_DQS_DP<11>
J 0
(660 4560);
DISPLAY 0.659574 (660 4560);
PAINT MONO (660 4560);
DISPLAY INVISIBLE (660 4560);
FORCEPROP 1 LASTPIN (650 4550) BN 11
J 2
(700 4560);
DISPLAY 0.617021 (700 4560);
PAINT PINK (700 4560);
FORCEPROP 2 LAST CDS_LIB mstr_standard
J 0
(700 4550);
DISPLAY 0.787234 (700 4550);
PAINT MONO (700 4550);
DISPLAY INVISIBLE (700 4550);
FORCEPROP 1 LAST BODY_TYPE PLUMBING
J 2
(700 4500);
DISPLAY 1.234043 (700 4500);
PAINT GREEN (700 4500);
DISPLAY INVISIBLE (700 4500);
FORCEPROP 1 LAST HDL_TAP TRUE
J 2
(375 4425);
DISPLAY 1.234043 (375 4425);
PAINT GREEN (375 4425);
DISPLAY INVISIBLE (375 4425);
FORCEPROP 1 LAST PATH I18
J 2
(700 4550);
DISPLAY 0.936170 (700 4550);
PAINT GREEN (700 4550);
DISPLAY INVISIBLE (700 4550);
FORCEADD PVPP_ABC..1
(-650 3000);
FORCEPROP 3 LASTPIN (-650 2950) SIG_NAME PVPP_ABC\g
J 0
(-640 2960);
DISPLAY 0.659574 (-640 2960);
PAINT MONO (-640 2960);
DISPLAY INVISIBLE (-640 2960);
FORCEPROP 1 LAST VOLTAGE 2.5V
J 0
(-695 2957);
DISPLAY 0.340426 (-695 2957);
PAINT SKYBLUE (-695 2957);
DISPLAY INVISIBLE (-695 2957);
FORCEPROP 0 LAST BOM_COST MEM
J 0
(-650 3100);
PAINT ORANGE (-650 3100);
DISPLAY INVISIBLE (-650 3100);
FORCEPROP 2 LAST CDS_LIB mstr_symbols
J 0
(-650 3000);
PAINT ORANGE (-650 3000);
DISPLAY INVISIBLE (-650 3000);
FORCEPROP 1 LAST BODY_TYPE PLUMBING
J 0
(-695 2957);
DISPLAY 0.340426 (-695 2957);
PAINT GREEN (-695 2957);
DISPLAY INVISIBLE (-695 2957);
FORCEPROP 1 LAST PATH I180
J 0
(-600 3025);
DISPLAY 0.872340 (-600 3025);
PAINT AQUA (-600 3025);
DISPLAY INVISIBLE (-600 3025);
FORCEPROP 2 LAST ROOM DDR4_CH_A
J 0
(-650 3100);
PAINT ORANGE (-650 3100);
DISPLAY INVISIBLE (-650 3100);
FORCEPROP 1 LAST HDL_POWER PVPP_ABC
J 1
(-650 3050);
DISPLAY 0.872340 (-650 3050);
PAINT GREEN (-650 3050);
DISPLAY INVISIBLE (-650 3050);
FORCEADD PVPP_ABC..1
(-5050 1950);
FORCEPROP 3 LASTPIN (-5050 1900) SIG_NAME PVPP_ABC\g
J 0
(-5040 1910);
DISPLAY 0.659574 (-5040 1910);
PAINT MONO (-5040 1910);
DISPLAY INVISIBLE (-5040 1910);
FORCEPROP 1 LAST VOLTAGE 2.5V
J 0
(-5095 1907);
DISPLAY 0.340426 (-5095 1907);
PAINT SKYBLUE (-5095 1907);
DISPLAY INVISIBLE (-5095 1907);
FORCEPROP 0 LAST BOM_COST MEM
J 0
(-5050 2050);
PAINT ORANGE (-5050 2050);
DISPLAY INVISIBLE (-5050 2050);
FORCEPROP 2 LAST CDS_LIB mstr_symbols
J 0
(-5050 1950);
PAINT ORANGE (-5050 1950);
DISPLAY INVISIBLE (-5050 1950);
FORCEPROP 1 LAST BODY_TYPE PLUMBING
J 0
(-5095 1907);
DISPLAY 0.340426 (-5095 1907);
PAINT GREEN (-5095 1907);
DISPLAY INVISIBLE (-5095 1907);
FORCEPROP 1 LAST PATH I181
J 0
(-5000 1975);
DISPLAY 0.872340 (-5000 1975);
PAINT AQUA (-5000 1975);
DISPLAY INVISIBLE (-5000 1975);
FORCEPROP 2 LAST ROOM DDR4_CH_A
J 0
(-5050 2050);
PAINT ORANGE (-5050 2050);
DISPLAY INVISIBLE (-5050 2050);
FORCEPROP 1 LAST HDL_POWER PVPP_ABC
J 1
(-5050 2000);
DISPLAY 0.872340 (-5050 2000);
PAINT GREEN (-5050 2000);
DISPLAY INVISIBLE (-5050 2000);
FORCEADD OFFPAGE..1
(-3850 1150);
FORCEPROP 2 LAST $XR5 48 
J 0
(-4551 1150);
DISPLAY 0.638298 (-4551 1150);
PAINT MONO (-4551 1150);
FORCEPROP 2 LAST $XR4 47 
J 0
(-4461 1150);
DISPLAY 0.638298 (-4461 1150);
PAINT MONO (-4461 1150);
FORCEPROP 2 LAST $XR3 46 
J 0
(-4371 1150);
DISPLAY 0.638298 (-4371 1150);
PAINT MONO (-4371 1150);
FORCEPROP 2 LAST $XR2 44 
J 0
(-4281 1150);
DISPLAY 0.638298 (-4281 1150);
PAINT MONO (-4281 1150);
FORCEPROP 2 LAST $XR1 43 
J 0
(-4191 1150);
DISPLAY 0.638298 (-4191 1150);
PAINT MONO (-4191 1150);
FORCEPROP 2 LAST $XR0 89 
J 0
(-4101 1150);
DISPLAY 0.638298 (-4101 1150);
PAINT MONO (-4101 1150);
FORCEPROP 2 LAST CDS_LIB mstr_standard
J 0
(-3850 1150);
PAINT ORANGE (-3850 1150);
DISPLAY INVISIBLE (-3850 1150);
FORCEPROP 1 LAST OFFPAGE TRUE
J 0
(-3525 1025);
DISPLAY 0.936170 (-3525 1025);
PAINT GREEN (-3525 1025);
DISPLAY INVISIBLE (-3525 1025);
FORCEPROP 1 LAST COMMENT_BODY TRUE
J 0
(-3725 1050);
DISPLAY 0.936170 (-3725 1050);
PAINT GREEN (-3725 1050);
DISPLAY INVISIBLE (-3725 1050);
FORCEPROP 2 LAST PATH I182
J 0
(-3800 1225);
PAINT ORANGE (-3800 1225);
DISPLAY INVISIBLE (-3800 1225);
FORCEADD P12V_NVDIMM_ABC..1
(750 3075);
FORCEPROP 3 LASTPIN (750 3025) SIG_NAME P12V_NVDIMM_ABC\g
J 0
(760 3035);
DISPLAY 0.659574 (760 3035);
PAINT MONO (760 3035);
DISPLAY INVISIBLE (760 3035);
FORCEPROP 1 LAST VOLTAGE 12.0
J 0
(705 3032);
DISPLAY 0.340426 (705 3032);
PAINT SKYBLUE (705 3032);
DISPLAY INVISIBLE (705 3032);
FORCEPROP 2 LAST CDS_LIB mstr_symbols
J 0
(750 3075);
PAINT ORANGE (750 3075);
DISPLAY INVISIBLE (750 3075);
FORCEPROP 1 LAST BODY_TYPE PLUMBING
J 0
(705 3032);
DISPLAY 0.340426 (705 3032);
PAINT GREEN (705 3032);
DISPLAY INVISIBLE (705 3032);
FORCEPROP 1 LAST PATH I183
J 0
(800 3100);
DISPLAY 0.872340 (800 3100);
PAINT AQUA (800 3100);
DISPLAY INVISIBLE (800 3100);
FORCEPROP 1 LAST HDL_POWER P12V_NVDIMM_ABC
J 1
(750 3100);
DISPLAY 0.872340 (750 3100);
PAINT GREEN (750 3100);
DISPLAY INVISIBLE (750 3100);
FORCEADD TAP..6
R 2
(900 4400);
FORCEPROP 3 LASTPIN (850 4400) SIG_NAME M_B_DQS_DN<10>
J 0
(860 4410);
DISPLAY 0.659574 (860 4410);
PAINT MONO (860 4410);
DISPLAY INVISIBLE (860 4410);
FORCEPROP 1 LASTPIN (850 4400) BN 10
J 2
(900 4410);
DISPLAY 0.617021 (900 4410);
PAINT PINK (900 4410);
FORCEPROP 2 LAST CDS_LIB mstr_standard
J 0
(900 4400);
DISPLAY 0.787234 (900 4400);
PAINT MONO (900 4400);
DISPLAY INVISIBLE (900 4400);
FORCEPROP 1 LAST BODY_TYPE PLUMBING
J 2
(900 4350);
DISPLAY 1.234043 (900 4350);
PAINT GREEN (900 4350);
DISPLAY INVISIBLE (900 4350);
FORCEPROP 1 LAST HDL_TAP TRUE
J 2
(575 4275);
DISPLAY 1.234043 (575 4275);
PAINT GREEN (575 4275);
DISPLAY INVISIBLE (575 4275);
FORCEPROP 1 LAST PATH I19
J 2
(900 4400);
DISPLAY 0.936170 (900 4400);
PAINT GREEN (900 4400);
DISPLAY INVISIBLE (900 4400);
FORCEADD OFFPAGE..3
(1600 5150);
FORCEPROP 2 LAST $XR1 46 
J 0
(1904 5150);
DISPLAY 0.638298 (1904 5150);
PAINT MONO (1904 5150);
FORCEPROP 2 LAST $XR0 24 
J 0
(1814 5150);
DISPLAY 0.638298 (1814 5150);
PAINT MONO (1814 5150);
FORCEPROP 2 LAST CDS_LIB mstr_standard
J 0
(1600 5150);
DISPLAY 0.787234 (1600 5150);
PAINT MONO (1600 5150);
DISPLAY INVISIBLE (1600 5150);
FORCEPROP 1 LAST OFFPAGE TRUE
J 0
(1925 5025);
DISPLAY 0.936170 (1925 5025);
PAINT GREEN (1925 5025);
DISPLAY INVISIBLE (1925 5025);
FORCEPROP 1 LAST COMMENT_BODY TRUE
J 0
(1550 5050);
DISPLAY 0.936170 (1550 5050);
PAINT GREEN (1550 5050);
DISPLAY INVISIBLE (1550 5050);
FORCEPROP 2 LAST PATH I2
J 0
(1800 5225);
DISPLAY 0.787234 (1800 5225);
PAINT MONO (1800 5225);
DISPLAY INVISIBLE (1800 5225);
FORCEADD TAP..6
R 2
(900 4500);
FORCEPROP 3 LASTPIN (850 4500) SIG_NAME M_B_DQS_DN<11>
J 0
(860 4510);
DISPLAY 0.659574 (860 4510);
PAINT MONO (860 4510);
DISPLAY INVISIBLE (860 4510);
FORCEPROP 1 LASTPIN (850 4500) BN 11
J 2
(900 4510);
DISPLAY 0.617021 (900 4510);
PAINT PINK (900 4510);
FORCEPROP 2 LAST CDS_LIB mstr_standard
J 0
(900 4500);
DISPLAY 0.787234 (900 4500);
PAINT MONO (900 4500);
DISPLAY INVISIBLE (900 4500);
FORCEPROP 1 LAST BODY_TYPE PLUMBING
J 2
(900 4450);
DISPLAY 1.234043 (900 4450);
PAINT GREEN (900 4450);
DISPLAY INVISIBLE (900 4450);
FORCEPROP 1 LAST HDL_TAP TRUE
J 2
(575 4375);
DISPLAY 1.234043 (575 4375);
PAINT GREEN (575 4375);
DISPLAY INVISIBLE (575 4375);
FORCEPROP 1 LAST PATH I20
J 2
(900 4500);
DISPLAY 0.936170 (900 4500);
PAINT GREEN (900 4500);
DISPLAY INVISIBLE (900 4500);
FORCEADD TAP..6
R 2
(900 4300);
FORCEPROP 3 LASTPIN (850 4300) SIG_NAME M_B_DQS_DN<9>
J 0
(860 4310);
DISPLAY 0.659574 (860 4310);
PAINT MONO (860 4310);
DISPLAY INVISIBLE (860 4310);
FORCEPROP 1 LASTPIN (850 4300) BN 9
J 2
(900 4310);
DISPLAY 0.617021 (900 4310);
PAINT PINK (900 4310);
FORCEPROP 2 LAST CDS_LIB mstr_standard
J 0
(900 4300);
DISPLAY 0.787234 (900 4300);
PAINT MONO (900 4300);
DISPLAY INVISIBLE (900 4300);
FORCEPROP 1 LAST BODY_TYPE PLUMBING
J 2
(900 4250);
DISPLAY 1.234043 (900 4250);
PAINT GREEN (900 4250);
DISPLAY INVISIBLE (900 4250);
FORCEPROP 1 LAST HDL_TAP TRUE
J 2
(575 4175);
DISPLAY 1.234043 (575 4175);
PAINT GREEN (575 4175);
DISPLAY INVISIBLE (575 4175);
FORCEPROP 1 LAST PATH I21
J 2
(900 4300);
DISPLAY 0.936170 (900 4300);
PAINT GREEN (900 4300);
DISPLAY INVISIBLE (900 4300);
FORCEADD TAP..6
R 2
(700 4450);
FORCEPROP 3 LASTPIN (650 4450) SIG_NAME M_B_DQS_DP<10>
J 0
(660 4460);
DISPLAY 0.659574 (660 4460);
PAINT MONO (660 4460);
DISPLAY INVISIBLE (660 4460);
FORCEPROP 1 LASTPIN (650 4450) BN 10
J 2
(700 4460);
DISPLAY 0.617021 (700 4460);
PAINT PINK (700 4460);
FORCEPROP 2 LAST CDS_LIB mstr_standard
J 0
(700 4450);
DISPLAY 0.787234 (700 4450);
PAINT MONO (700 4450);
DISPLAY INVISIBLE (700 4450);
FORCEPROP 1 LAST BODY_TYPE PLUMBING
J 2
(700 4400);
DISPLAY 1.234043 (700 4400);
PAINT GREEN (700 4400);
DISPLAY INVISIBLE (700 4400);
FORCEPROP 1 LAST HDL_TAP TRUE
J 2
(375 4325);
DISPLAY 1.234043 (375 4325);
PAINT GREEN (375 4325);
DISPLAY INVISIBLE (375 4325);
FORCEPROP 1 LAST PATH I22
J 2
(700 4450);
DISPLAY 0.936170 (700 4450);
PAINT GREEN (700 4450);
DISPLAY INVISIBLE (700 4450);
FORCEADD TAP..6
R 2
(700 4350);
FORCEPROP 3 LASTPIN (650 4350) SIG_NAME M_B_DQS_DP<9>
J 0
(660 4360);
DISPLAY 0.659574 (660 4360);
PAINT MONO (660 4360);
DISPLAY INVISIBLE (660 4360);
FORCEPROP 1 LASTPIN (650 4350) BN 9
J 2
(700 4360);
DISPLAY 0.617021 (700 4360);
PAINT PINK (700 4360);
FORCEPROP 2 LAST CDS_LIB mstr_standard
J 0
(700 4350);
DISPLAY 0.787234 (700 4350);
PAINT MONO (700 4350);
DISPLAY INVISIBLE (700 4350);
FORCEPROP 1 LAST BODY_TYPE PLUMBING
J 2
(700 4300);
DISPLAY 1.234043 (700 4300);
PAINT GREEN (700 4300);
DISPLAY INVISIBLE (700 4300);
FORCEPROP 1 LAST HDL_TAP TRUE
J 2
(375 4225);
DISPLAY 1.234043 (375 4225);
PAINT GREEN (375 4225);
DISPLAY INVISIBLE (375 4225);
FORCEPROP 1 LAST PATH I23
J 2
(700 4350);
DISPLAY 0.936170 (700 4350);
PAINT GREEN (700 4350);
DISPLAY INVISIBLE (700 4350);
FORCEADD TAP..6
R 2
(900 4100);
FORCEPROP 3 LASTPIN (850 4100) SIG_NAME M_B_DQS_DN<7>
J 0
(860 4110);
DISPLAY 0.659574 (860 4110);
PAINT MONO (860 4110);
DISPLAY INVISIBLE (860 4110);
FORCEPROP 1 LASTPIN (850 4100) BN 7
J 2
(900 4110);
DISPLAY 0.617021 (900 4110);
PAINT PINK (900 4110);
FORCEPROP 2 LAST CDS_LIB mstr_standard
J 0
(900 4100);
DISPLAY 0.787234 (900 4100);
PAINT MONO (900 4100);
DISPLAY INVISIBLE (900 4100);
FORCEPROP 1 LAST BODY_TYPE PLUMBING
J 2
(900 4050);
DISPLAY 1.234043 (900 4050);
PAINT GREEN (900 4050);
DISPLAY INVISIBLE (900 4050);
FORCEPROP 1 LAST HDL_TAP TRUE
J 2
(575 3975);
DISPLAY 1.234043 (575 3975);
PAINT GREEN (575 3975);
DISPLAY INVISIBLE (575 3975);
FORCEPROP 1 LAST PATH I24
J 2
(900 4100);
DISPLAY 0.936170 (900 4100);
PAINT GREEN (900 4100);
DISPLAY INVISIBLE (900 4100);
FORCEADD TAP..6
R 2
(900 4200);
FORCEPROP 3 LASTPIN (850 4200) SIG_NAME M_B_DQS_DN<8>
J 0
(860 4210);
DISPLAY 0.659574 (860 4210);
PAINT MONO (860 4210);
DISPLAY INVISIBLE (860 4210);
FORCEPROP 1 LASTPIN (850 4200) BN 8
J 2
(900 4210);
DISPLAY 0.617021 (900 4210);
PAINT PINK (900 4210);
FORCEPROP 2 LAST CDS_LIB mstr_standard
J 0
(900 4200);
DISPLAY 0.787234 (900 4200);
PAINT MONO (900 4200);
DISPLAY INVISIBLE (900 4200);
FORCEPROP 1 LAST BODY_TYPE PLUMBING
J 2
(900 4150);
DISPLAY 1.234043 (900 4150);
PAINT GREEN (900 4150);
DISPLAY INVISIBLE (900 4150);
FORCEPROP 1 LAST HDL_TAP TRUE
J 2
(575 4075);
DISPLAY 1.234043 (575 4075);
PAINT GREEN (575 4075);
DISPLAY INVISIBLE (575 4075);
FORCEPROP 1 LAST PATH I25
J 2
(900 4200);
DISPLAY 0.936170 (900 4200);
PAINT GREEN (900 4200);
DISPLAY INVISIBLE (900 4200);
FORCEADD TAP..6
R 2
(700 4250);
FORCEPROP 3 LASTPIN (650 4250) SIG_NAME M_B_DQS_DP<8>
J 0
(660 4260);
DISPLAY 0.659574 (660 4260);
PAINT MONO (660 4260);
DISPLAY INVISIBLE (660 4260);
FORCEPROP 1 LASTPIN (650 4250) BN 8
J 2
(700 4260);
DISPLAY 0.617021 (700 4260);
PAINT PINK (700 4260);
FORCEPROP 2 LAST CDS_LIB mstr_standard
J 0
(700 4250);
DISPLAY 0.787234 (700 4250);
PAINT MONO (700 4250);
DISPLAY INVISIBLE (700 4250);
FORCEPROP 1 LAST BODY_TYPE PLUMBING
J 2
(700 4200);
DISPLAY 1.234043 (700 4200);
PAINT GREEN (700 4200);
DISPLAY INVISIBLE (700 4200);
FORCEPROP 1 LAST HDL_TAP TRUE
J 2
(375 4125);
DISPLAY 1.234043 (375 4125);
PAINT GREEN (375 4125);
DISPLAY INVISIBLE (375 4125);
FORCEPROP 1 LAST PATH I26
J 2
(700 4250);
DISPLAY 0.936170 (700 4250);
PAINT GREEN (700 4250);
DISPLAY INVISIBLE (700 4250);
FORCEADD TAP..6
R 2
(700 4150);
FORCEPROP 3 LASTPIN (650 4150) SIG_NAME M_B_DQS_DP<7>
J 0
(660 4160);
DISPLAY 0.659574 (660 4160);
PAINT MONO (660 4160);
DISPLAY INVISIBLE (660 4160);
FORCEPROP 1 LASTPIN (650 4150) BN 7
J 2
(700 4160);
DISPLAY 0.617021 (700 4160);
PAINT PINK (700 4160);
FORCEPROP 2 LAST CDS_LIB mstr_standard
J 0
(700 4150);
DISPLAY 0.787234 (700 4150);
PAINT MONO (700 4150);
DISPLAY INVISIBLE (700 4150);
FORCEPROP 1 LAST BODY_TYPE PLUMBING
J 2
(700 4100);
DISPLAY 1.234043 (700 4100);
PAINT GREEN (700 4100);
DISPLAY INVISIBLE (700 4100);
FORCEPROP 1 LAST HDL_TAP TRUE
J 2
(375 4025);
DISPLAY 1.234043 (375 4025);
PAINT GREEN (375 4025);
DISPLAY INVISIBLE (375 4025);
FORCEPROP 1 LAST PATH I27
J 2
(700 4150);
DISPLAY 0.936170 (700 4150);
PAINT GREEN (700 4150);
DISPLAY INVISIBLE (700 4150);
FORCEADD TAP..6
R 2
(700 4050);
FORCEPROP 3 LASTPIN (650 4050) SIG_NAME M_B_DQS_DP<6>
J 0
(660 4060);
DISPLAY 0.659574 (660 4060);
PAINT MONO (660 4060);
DISPLAY INVISIBLE (660 4060);
FORCEPROP 1 LASTPIN (650 4050) BN 6
J 2
(700 4060);
DISPLAY 0.617021 (700 4060);
PAINT PINK (700 4060);
FORCEPROP 2 LAST CDS_LIB mstr_standard
J 0
(700 4050);
DISPLAY 0.787234 (700 4050);
PAINT MONO (700 4050);
DISPLAY INVISIBLE (700 4050);
FORCEPROP 1 LAST BODY_TYPE PLUMBING
J 2
(700 4000);
DISPLAY 1.234043 (700 4000);
PAINT GREEN (700 4000);
DISPLAY INVISIBLE (700 4000);
FORCEPROP 1 LAST HDL_TAP TRUE
J 2
(375 3925);
DISPLAY 1.234043 (375 3925);
PAINT GREEN (375 3925);
DISPLAY INVISIBLE (375 3925);
FORCEPROP 1 LAST PATH I28
J 2
(700 4050);
DISPLAY 0.936170 (700 4050);
PAINT GREEN (700 4050);
DISPLAY INVISIBLE (700 4050);
FORCEADD TAP..6
R 2
(900 3900);
FORCEPROP 3 LASTPIN (850 3900) SIG_NAME M_B_DQS_DN<5>
J 0
(860 3910);
DISPLAY 0.659574 (860 3910);
PAINT MONO (860 3910);
DISPLAY INVISIBLE (860 3910);
FORCEPROP 1 LASTPIN (850 3900) BN 5
J 2
(900 3910);
DISPLAY 0.617021 (900 3910);
PAINT PINK (900 3910);
FORCEPROP 2 LAST CDS_LIB mstr_standard
J 0
(900 3900);
DISPLAY 0.787234 (900 3900);
PAINT MONO (900 3900);
DISPLAY INVISIBLE (900 3900);
FORCEPROP 1 LAST BODY_TYPE PLUMBING
J 2
(900 3850);
DISPLAY 1.234043 (900 3850);
PAINT GREEN (900 3850);
DISPLAY INVISIBLE (900 3850);
FORCEPROP 1 LAST HDL_TAP TRUE
J 2
(575 3775);
DISPLAY 1.234043 (575 3775);
PAINT GREEN (575 3775);
DISPLAY INVISIBLE (575 3775);
FORCEPROP 1 LAST PATH I29
J 2
(900 3900);
DISPLAY 0.936170 (900 3900);
PAINT GREEN (900 3900);
DISPLAY INVISIBLE (900 3900);
FORCEADD TAP..6
R 2
(900 5100);
FORCEPROP 3 LASTPIN (850 5100) SIG_NAME M_B_DQS_DN<17>
J 0
(860 5110);
DISPLAY 0.659574 (860 5110);
PAINT MONO (860 5110);
DISPLAY INVISIBLE (860 5110);
FORCEPROP 1 LASTPIN (850 5100) BN 17
J 2
(900 5110);
DISPLAY 0.617021 (900 5110);
PAINT PINK (900 5110);
FORCEPROP 2 LAST CDS_LIB mstr_standard
J 2
(900 5100);
DISPLAY 0.787234 (900 5100);
PAINT MONO (900 5100);
DISPLAY INVISIBLE (900 5100);
FORCEPROP 1 LAST BODY_TYPE PLUMBING
J 2
(900 5050);
DISPLAY 1.234043 (900 5050);
PAINT GREEN (900 5050);
DISPLAY INVISIBLE (900 5050);
FORCEPROP 1 LAST HDL_TAP TRUE
J 2
(575 4975);
DISPLAY 1.234043 (575 4975);
PAINT GREEN (575 4975);
DISPLAY INVISIBLE (575 4975);
FORCEPROP 1 LAST PATH I3
J 2
(900 5100);
DISPLAY 0.936170 (900 5100);
PAINT GREEN (900 5100);
DISPLAY INVISIBLE (900 5100);
FORCEADD TAP..6
R 2
(900 4000);
FORCEPROP 3 LASTPIN (850 4000) SIG_NAME M_B_DQS_DN<6>
J 0
(860 4010);
DISPLAY 0.659574 (860 4010);
PAINT MONO (860 4010);
DISPLAY INVISIBLE (860 4010);
FORCEPROP 1 LASTPIN (850 4000) BN 6
J 2
(900 4010);
DISPLAY 0.617021 (900 4010);
PAINT PINK (900 4010);
FORCEPROP 2 LAST CDS_LIB mstr_standard
J 0
(900 4000);
DISPLAY 0.787234 (900 4000);
PAINT MONO (900 4000);
DISPLAY INVISIBLE (900 4000);
FORCEPROP 1 LAST BODY_TYPE PLUMBING
J 2
(900 3950);
DISPLAY 1.234043 (900 3950);
PAINT GREEN (900 3950);
DISPLAY INVISIBLE (900 3950);
FORCEPROP 1 LAST HDL_TAP TRUE
J 2
(575 3875);
DISPLAY 1.234043 (575 3875);
PAINT GREEN (575 3875);
DISPLAY INVISIBLE (575 3875);
FORCEPROP 1 LAST PATH I30
J 2
(900 4000);
DISPLAY 0.936170 (900 4000);
PAINT GREEN (900 4000);
DISPLAY INVISIBLE (900 4000);
FORCEADD TAP..6
R 2
(900 3800);
FORCEPROP 3 LASTPIN (850 3800) SIG_NAME M_B_DQS_DN<4>
J 0
(860 3810);
DISPLAY 0.659574 (860 3810);
PAINT MONO (860 3810);
DISPLAY INVISIBLE (860 3810);
FORCEPROP 1 LASTPIN (850 3800) BN 4
J 2
(900 3810);
DISPLAY 0.617021 (900 3810);
PAINT PINK (900 3810);
FORCEPROP 2 LAST CDS_LIB mstr_standard
J 0
(900 3800);
DISPLAY 0.787234 (900 3800);
PAINT MONO (900 3800);
DISPLAY INVISIBLE (900 3800);
FORCEPROP 1 LAST BODY_TYPE PLUMBING
J 2
(900 3750);
DISPLAY 1.234043 (900 3750);
PAINT GREEN (900 3750);
DISPLAY INVISIBLE (900 3750);
FORCEPROP 1 LAST HDL_TAP TRUE
J 2
(575 3675);
DISPLAY 1.234043 (575 3675);
PAINT GREEN (575 3675);
DISPLAY INVISIBLE (575 3675);
FORCEPROP 1 LAST PATH I31
J 2
(900 3800);
DISPLAY 0.936170 (900 3800);
PAINT GREEN (900 3800);
DISPLAY INVISIBLE (900 3800);
FORCEADD TAP..6
R 2
(700 3950);
FORCEPROP 3 LASTPIN (650 3950) SIG_NAME M_B_DQS_DP<5>
J 0
(660 3960);
DISPLAY 0.659574 (660 3960);
PAINT MONO (660 3960);
DISPLAY INVISIBLE (660 3960);
FORCEPROP 1 LASTPIN (650 3950) BN 5
J 2
(700 3960);
DISPLAY 0.617021 (700 3960);
PAINT PINK (700 3960);
FORCEPROP 2 LAST CDS_LIB mstr_standard
J 0
(700 3950);
DISPLAY 0.787234 (700 3950);
PAINT MONO (700 3950);
DISPLAY INVISIBLE (700 3950);
FORCEPROP 1 LAST BODY_TYPE PLUMBING
J 2
(700 3900);
DISPLAY 1.234043 (700 3900);
PAINT GREEN (700 3900);
DISPLAY INVISIBLE (700 3900);
FORCEPROP 1 LAST HDL_TAP TRUE
J 2
(375 3825);
DISPLAY 1.234043 (375 3825);
PAINT GREEN (375 3825);
DISPLAY INVISIBLE (375 3825);
FORCEPROP 1 LAST PATH I32
J 2
(700 3950);
DISPLAY 0.936170 (700 3950);
PAINT GREEN (700 3950);
DISPLAY INVISIBLE (700 3950);
FORCEADD TAP..6
R 2
(700 3850);
FORCEPROP 3 LASTPIN (650 3850) SIG_NAME M_B_DQS_DP<4>
J 0
(660 3860);
DISPLAY 0.659574 (660 3860);
PAINT MONO (660 3860);
DISPLAY INVISIBLE (660 3860);
FORCEPROP 1 LASTPIN (650 3850) BN 4
J 2
(700 3860);
DISPLAY 0.617021 (700 3860);
PAINT PINK (700 3860);
FORCEPROP 2 LAST CDS_LIB mstr_standard
J 0
(700 3850);
DISPLAY 0.787234 (700 3850);
PAINT MONO (700 3850);
DISPLAY INVISIBLE (700 3850);
FORCEPROP 1 LAST BODY_TYPE PLUMBING
J 2
(700 3800);
DISPLAY 1.234043 (700 3800);
PAINT GREEN (700 3800);
DISPLAY INVISIBLE (700 3800);
FORCEPROP 1 LAST HDL_TAP TRUE
J 2
(375 3725);
DISPLAY 1.234043 (375 3725);
PAINT GREEN (375 3725);
DISPLAY INVISIBLE (375 3725);
FORCEPROP 1 LAST PATH I33
J 2
(700 3850);
DISPLAY 0.936170 (700 3850);
PAINT GREEN (700 3850);
DISPLAY INVISIBLE (700 3850);
FORCEADD TAP..6
R 2
(700 3750);
FORCEPROP 3 LASTPIN (650 3750) SIG_NAME M_B_DQS_DP<3>
J 0
(660 3760);
DISPLAY 0.659574 (660 3760);
PAINT MONO (660 3760);
DISPLAY INVISIBLE (660 3760);
FORCEPROP 1 LASTPIN (650 3750) BN 3
J 2
(700 3760);
DISPLAY 0.617021 (700 3760);
PAINT PINK (700 3760);
FORCEPROP 2 LAST CDS_LIB mstr_standard
J 0
(700 3750);
DISPLAY 0.787234 (700 3750);
PAINT MONO (700 3750);
DISPLAY INVISIBLE (700 3750);
FORCEPROP 1 LAST BODY_TYPE PLUMBING
J 2
(700 3700);
DISPLAY 1.234043 (700 3700);
PAINT GREEN (700 3700);
DISPLAY INVISIBLE (700 3700);
FORCEPROP 1 LAST HDL_TAP TRUE
J 2
(375 3625);
DISPLAY 1.234043 (375 3625);
PAINT GREEN (375 3625);
DISPLAY INVISIBLE (375 3625);
FORCEPROP 1 LAST PATH I34
J 2
(700 3750);
DISPLAY 0.936170 (700 3750);
PAINT GREEN (700 3750);
DISPLAY INVISIBLE (700 3750);
FORCEADD TAP..6
R 2
(900 3500);
FORCEPROP 3 LASTPIN (850 3500) SIG_NAME M_B_DQS_DN<1>
J 0
(860 3510);
DISPLAY 0.659574 (860 3510);
PAINT MONO (860 3510);
DISPLAY INVISIBLE (860 3510);
FORCEPROP 1 LASTPIN (850 3500) BN 1
J 2
(900 3510);
DISPLAY 0.617021 (900 3510);
PAINT PINK (900 3510);
FORCEPROP 2 LAST CDS_LIB mstr_standard
J 0
(900 3500);
DISPLAY 0.787234 (900 3500);
PAINT MONO (900 3500);
DISPLAY INVISIBLE (900 3500);
FORCEPROP 1 LAST BODY_TYPE PLUMBING
J 2
(900 3450);
DISPLAY 1.234043 (900 3450);
PAINT GREEN (900 3450);
DISPLAY INVISIBLE (900 3450);
FORCEPROP 1 LAST HDL_TAP TRUE
J 2
(575 3375);
DISPLAY 1.234043 (575 3375);
PAINT GREEN (575 3375);
DISPLAY INVISIBLE (575 3375);
FORCEPROP 1 LAST PATH I35
J 2
(900 3500);
DISPLAY 0.936170 (900 3500);
PAINT GREEN (900 3500);
DISPLAY INVISIBLE (900 3500);
FORCEADD TAP..6
R 2
(900 3600);
FORCEPROP 3 LASTPIN (850 3600) SIG_NAME M_B_DQS_DN<2>
J 0
(860 3610);
DISPLAY 0.659574 (860 3610);
PAINT MONO (860 3610);
DISPLAY INVISIBLE (860 3610);
FORCEPROP 1 LASTPIN (850 3600) BN 2
J 2
(900 3610);
DISPLAY 0.617021 (900 3610);
PAINT PINK (900 3610);
FORCEPROP 2 LAST CDS_LIB mstr_standard
J 0
(900 3600);
DISPLAY 0.787234 (900 3600);
PAINT MONO (900 3600);
DISPLAY INVISIBLE (900 3600);
FORCEPROP 1 LAST BODY_TYPE PLUMBING
J 2
(900 3550);
DISPLAY 1.234043 (900 3550);
PAINT GREEN (900 3550);
DISPLAY INVISIBLE (900 3550);
FORCEPROP 1 LAST HDL_TAP TRUE
J 2
(575 3475);
DISPLAY 1.234043 (575 3475);
PAINT GREEN (575 3475);
DISPLAY INVISIBLE (575 3475);
FORCEPROP 1 LAST PATH I36
J 2
(900 3600);
DISPLAY 0.936170 (900 3600);
PAINT GREEN (900 3600);
DISPLAY INVISIBLE (900 3600);
FORCEADD TAP..6
R 2
(900 3700);
FORCEPROP 3 LASTPIN (850 3700) SIG_NAME M_B_DQS_DN<3>
J 0
(860 3710);
DISPLAY 0.659574 (860 3710);
PAINT MONO (860 3710);
DISPLAY INVISIBLE (860 3710);
FORCEPROP 1 LASTPIN (850 3700) BN 3
J 2
(900 3710);
DISPLAY 0.617021 (900 3710);
PAINT PINK (900 3710);
FORCEPROP 2 LAST CDS_LIB mstr_standard
J 0
(900 3700);
DISPLAY 0.787234 (900 3700);
PAINT MONO (900 3700);
DISPLAY INVISIBLE (900 3700);
FORCEPROP 1 LAST BODY_TYPE PLUMBING
J 2
(900 3650);
DISPLAY 1.234043 (900 3650);
PAINT GREEN (900 3650);
DISPLAY INVISIBLE (900 3650);
FORCEPROP 1 LAST HDL_TAP TRUE
J 2
(575 3575);
DISPLAY 1.234043 (575 3575);
PAINT GREEN (575 3575);
DISPLAY INVISIBLE (575 3575);
FORCEPROP 1 LAST PATH I37
J 2
(900 3700);
DISPLAY 0.936170 (900 3700);
PAINT GREEN (900 3700);
DISPLAY INVISIBLE (900 3700);
FORCEADD TAP..6
R 2
(700 3650);
FORCEPROP 3 LASTPIN (650 3650) SIG_NAME M_B_DQS_DP<2>
J 0
(660 3660);
DISPLAY 0.659574 (660 3660);
PAINT MONO (660 3660);
DISPLAY INVISIBLE (660 3660);
FORCEPROP 1 LASTPIN (650 3650) BN 2
J 2
(700 3660);
DISPLAY 0.617021 (700 3660);
PAINT PINK (700 3660);
FORCEPROP 2 LAST CDS_LIB mstr_standard
J 0
(700 3650);
DISPLAY 0.787234 (700 3650);
PAINT MONO (700 3650);
DISPLAY INVISIBLE (700 3650);
FORCEPROP 1 LAST BODY_TYPE PLUMBING
J 2
(700 3600);
DISPLAY 1.234043 (700 3600);
PAINT GREEN (700 3600);
DISPLAY INVISIBLE (700 3600);
FORCEPROP 1 LAST HDL_TAP TRUE
J 2
(375 3525);
DISPLAY 1.234043 (375 3525);
PAINT GREEN (375 3525);
DISPLAY INVISIBLE (375 3525);
FORCEPROP 1 LAST PATH I38
J 2
(700 3650);
DISPLAY 0.936170 (700 3650);
PAINT GREEN (700 3650);
DISPLAY INVISIBLE (700 3650);
FORCEADD TAP..6
R 2
(700 3550);
FORCEPROP 3 LASTPIN (650 3550) SIG_NAME M_B_DQS_DP<1>
J 0
(660 3560);
DISPLAY 0.659574 (660 3560);
PAINT MONO (660 3560);
DISPLAY INVISIBLE (660 3560);
FORCEPROP 1 LASTPIN (650 3550) BN 1
J 2
(700 3560);
DISPLAY 0.617021 (700 3560);
PAINT PINK (700 3560);
FORCEPROP 2 LAST CDS_LIB mstr_standard
J 0
(700 3550);
DISPLAY 0.787234 (700 3550);
PAINT MONO (700 3550);
DISPLAY INVISIBLE (700 3550);
FORCEPROP 1 LAST BODY_TYPE PLUMBING
J 2
(700 3500);
DISPLAY 1.234043 (700 3500);
PAINT GREEN (700 3500);
DISPLAY INVISIBLE (700 3500);
FORCEPROP 1 LAST HDL_TAP TRUE
J 2
(375 3425);
DISPLAY 1.234043 (375 3425);
PAINT GREEN (375 3425);
DISPLAY INVISIBLE (375 3425);
FORCEPROP 1 LAST PATH I39
J 2
(700 3550);
DISPLAY 0.936170 (700 3550);
PAINT GREEN (700 3550);
DISPLAY INVISIBLE (700 3550);
FORCEADD TAP..6
R 2
(700 5150);
FORCEPROP 3 LASTPIN (650 5150) SIG_NAME M_B_DQS_DP<17>
J 0
(660 5160);
DISPLAY 0.659574 (660 5160);
PAINT MONO (660 5160);
DISPLAY INVISIBLE (660 5160);
FORCEPROP 1 LASTPIN (650 5150) BN 17
J 2
(700 5160);
DISPLAY 0.617021 (700 5160);
PAINT PINK (700 5160);
FORCEPROP 2 LAST CDS_LIB mstr_standard
J 2
(700 5150);
DISPLAY 0.787234 (700 5150);
PAINT MONO (700 5150);
DISPLAY INVISIBLE (700 5150);
FORCEPROP 1 LAST BODY_TYPE PLUMBING
J 2
(700 5100);
DISPLAY 1.234043 (700 5100);
PAINT GREEN (700 5100);
DISPLAY INVISIBLE (700 5100);
FORCEPROP 1 LAST HDL_TAP TRUE
J 2
(375 5025);
DISPLAY 1.234043 (375 5025);
PAINT GREEN (375 5025);
DISPLAY INVISIBLE (375 5025);
FORCEPROP 1 LAST PATH I4
J 2
(700 5150);
DISPLAY 0.936170 (700 5150);
PAINT GREEN (700 5150);
DISPLAY INVISIBLE (700 5150);
FORCEADD TAP..6
R 2
(900 3400);
FORCEPROP 3 LASTPIN (850 3400) SIG_NAME M_B_DQS_DN<0>
J 0
(860 3410);
DISPLAY 0.659574 (860 3410);
PAINT MONO (860 3410);
DISPLAY INVISIBLE (860 3410);
FORCEPROP 1 LASTPIN (850 3400) BN 0
J 2
(900 3410);
DISPLAY 0.617021 (900 3410);
PAINT PINK (900 3410);
FORCEPROP 2 LAST CDS_LIB mstr_standard
J 0
(900 3400);
DISPLAY 0.787234 (900 3400);
PAINT MONO (900 3400);
DISPLAY INVISIBLE (900 3400);
FORCEPROP 1 LAST BODY_TYPE PLUMBING
J 2
(900 3350);
DISPLAY 1.234043 (900 3350);
PAINT GREEN (900 3350);
DISPLAY INVISIBLE (900 3350);
FORCEPROP 1 LAST HDL_TAP TRUE
J 2
(575 3275);
DISPLAY 1.234043 (575 3275);
PAINT GREEN (575 3275);
DISPLAY INVISIBLE (575 3275);
FORCEPROP 1 LAST PATH I40
J 2
(900 3400);
DISPLAY 0.936170 (900 3400);
PAINT GREEN (900 3400);
DISPLAY INVISIBLE (900 3400);
FORCEADD TAP..6
R 2
(700 3450);
FORCEPROP 3 LASTPIN (650 3450) SIG_NAME M_B_DQS_DP<0>
J 0
(660 3460);
DISPLAY 0.659574 (660 3460);
PAINT MONO (660 3460);
DISPLAY INVISIBLE (660 3460);
FORCEPROP 1 LASTPIN (650 3450) BN 0
J 2
(700 3460);
DISPLAY 0.617021 (700 3460);
PAINT PINK (700 3460);
FORCEPROP 2 LAST CDS_LIB mstr_standard
J 0
(700 3450);
DISPLAY 0.787234 (700 3450);
PAINT MONO (700 3450);
DISPLAY INVISIBLE (700 3450);
FORCEPROP 1 LAST BODY_TYPE PLUMBING
J 2
(700 3400);
DISPLAY 1.234043 (700 3400);
PAINT GREEN (700 3400);
DISPLAY INVISIBLE (700 3400);
FORCEPROP 1 LAST HDL_TAP TRUE
J 2
(375 3325);
DISPLAY 1.234043 (375 3325);
PAINT GREEN (375 3325);
DISPLAY INVISIBLE (375 3325);
FORCEPROP 1 LAST PATH I41
J 2
(700 3450);
DISPLAY 0.936170 (700 3450);
PAINT GREEN (700 3450);
DISPLAY INVISIBLE (700 3450);
FORCEADD GND..1
R 2
(2500 1300);
FORCEPROP 3 LASTPIN (2500 1350) SIG_NAME GND\g
J 0
(2510 1360);
DISPLAY 0.659574 (2510 1360);
PAINT MONO (2510 1360);
DISPLAY INVISIBLE (2510 1360);
FORCEPROP 1 LAST VOLTAGE 0
J 0
(2500 1300);
PAINT SKYBLUE (2500 1300);
DISPLAY INVISIBLE (2500 1300);
FORCEPROP 2 LAST BOM_COST MEM
J 0
(2500 1305);
PAINT ORANGE (2500 1305);
DISPLAY INVISIBLE (2500 1305);
FORCEPROP 2 LAST CDS_LIB mstr_symbols
J 0
(2500 1300);
DISPLAY 0.787234 (2500 1300);
PAINT MONO (2500 1300);
DISPLAY INVISIBLE (2500 1300);
FORCEPROP 1 LAST SIZE 1B
J 2
(2425 1250);
DISPLAY 1.170213 (2425 1250);
PAINT GREEN (2425 1250);
DISPLAY INVISIBLE (2425 1250);
FORCEPROP 1 LAST BODY_TYPE PLUMBING
J 2
(2545 1257);
DISPLAY 0.340426 (2545 1257);
PAINT GREEN (2545 1257);
DISPLAY INVISIBLE (2545 1257);
FORCEPROP 1 LAST PATH I42
J 2
(2425 1300);
DISPLAY 0.936170 (2425 1300);
PAINT GREEN (2425 1300);
DISPLAY INVISIBLE (2425 1300);
FORCEPROP 2 LAST ROOM DDR4_CH_A
J 0
(2500 1305);
PAINT ORANGE (2500 1305);
DISPLAY INVISIBLE (2500 1305);
FORCEPROP 1 LAST HDL_POWER GND
J 2
(2500 1450);
DISPLAY 0.553191 (2500 1450);
PAINT GREEN (2500 1450);
DISPLAY INVISIBLE (2500 1450);
FORCEADD SCONN288_H44441004..3
(1800 2600);
FORCEPROP 1 LAST LOCATION J4G2
J 0
(1350 4000);
DISPLAY 0.617021 (1350 4000);
PAINT AQUA (1350 4000);
FORCEPROP 1 LAST PART_NUMBER H44441-004
J 0
(1350 1250);
DISPLAY 0.617021 (1350 1250);
PAINT BLUE (1350 1250);
FORCEPROP 1 LAST MATERIAL SCONN
J 0
(1350 3950);
DISPLAY 0.617021 (1350 3950);
PAINT SKYBLUE (1350 3950);
FORCEPROP 2 LASTPIN (1300 3750) $PN 2
J 2
(1290 3760);
DISPLAY 0.617021 (1290 3760);
PAINT ORANGE (1290 3760);
FORCEPROP 2 LASTPIN (1300 3700) $PN 4
J 2
(1290 3710);
DISPLAY 0.617021 (1290 3710);
PAINT ORANGE (1290 3710);
FORCEPROP 2 LASTPIN (1300 3650) $PN 6
J 2
(1290 3660);
DISPLAY 0.617021 (1290 3660);
PAINT ORANGE (1290 3660);
FORCEPROP 2 LASTPIN (1300 3600) $PN 9
J 2
(1290 3610);
DISPLAY 0.617021 (1290 3610);
PAINT ORANGE (1290 3610);
FORCEPROP 2 LASTPIN (1300 3550) $PN 11
J 2
(1290 3560);
DISPLAY 0.617021 (1290 3560);
PAINT ORANGE (1290 3560);
FORCEPROP 2 LASTPIN (1300 3500) $PN 13
J 2
(1290 3510);
DISPLAY 0.617021 (1290 3510);
PAINT ORANGE (1290 3510);
FORCEPROP 2 LASTPIN (1300 3450) $PN 15
J 2
(1290 3460);
DISPLAY 0.617021 (1290 3460);
PAINT ORANGE (1290 3460);
FORCEPROP 2 LASTPIN (1300 3400) $PN 17
J 2
(1290 3410);
DISPLAY 0.617021 (1290 3410);
PAINT ORANGE (1290 3410);
FORCEPROP 2 LASTPIN (1300 3350) $PN 20
J 2
(1290 3360);
DISPLAY 0.617021 (1290 3360);
PAINT ORANGE (1290 3360);
FORCEPROP 2 LASTPIN (1300 3300) $PN 22
J 2
(1290 3310);
DISPLAY 0.617021 (1290 3310);
PAINT ORANGE (1290 3310);
FORCEPROP 2 LASTPIN (1300 3250) $PN 24
J 2
(1290 3260);
DISPLAY 0.617021 (1290 3260);
PAINT ORANGE (1290 3260);
FORCEPROP 2 LASTPIN (1300 3200) $PN 26
J 2
(1290 3210);
DISPLAY 0.617021 (1290 3210);
PAINT ORANGE (1290 3210);
FORCEPROP 2 LASTPIN (1300 3150) $PN 28
J 2
(1290 3160);
DISPLAY 0.617021 (1290 3160);
PAINT ORANGE (1290 3160);
FORCEPROP 2 LASTPIN (1300 3100) $PN 31
J 2
(1290 3110);
DISPLAY 0.617021 (1290 3110);
PAINT ORANGE (1290 3110);
FORCEPROP 2 LASTPIN (1300 3050) $PN 33
J 2
(1290 3060);
DISPLAY 0.617021 (1290 3060);
PAINT ORANGE (1290 3060);
FORCEPROP 2 LASTPIN (1300 3000) $PN 35
J 2
(1290 3010);
DISPLAY 0.617021 (1290 3010);
PAINT ORANGE (1290 3010);
FORCEPROP 2 LASTPIN (1300 2950) $PN 37
J 2
(1290 2960);
DISPLAY 0.617021 (1290 2960);
PAINT ORANGE (1290 2960);
FORCEPROP 2 LASTPIN (1300 2900) $PN 39
J 2
(1290 2910);
DISPLAY 0.617021 (1290 2910);
PAINT ORANGE (1290 2910);
FORCEPROP 2 LASTPIN (1300 2850) $PN 42
J 2
(1290 2860);
DISPLAY 0.617021 (1290 2860);
PAINT ORANGE (1290 2860);
FORCEPROP 2 LASTPIN (1300 2800) $PN 44
J 2
(1290 2810);
DISPLAY 0.617021 (1290 2810);
PAINT ORANGE (1290 2810);
FORCEPROP 2 LASTPIN (1300 2750) $PN 46
J 2
(1290 2760);
DISPLAY 0.617021 (1290 2760);
PAINT ORANGE (1290 2760);
FORCEPROP 2 LASTPIN (1300 2700) $PN 48
J 2
(1290 2710);
DISPLAY 0.617021 (1290 2710);
PAINT ORANGE (1290 2710);
FORCEPROP 2 LASTPIN (1300 2650) $PN 50
J 2
(1290 2660);
DISPLAY 0.617021 (1290 2660);
PAINT ORANGE (1290 2660);
FORCEPROP 2 LASTPIN (1300 2600) $PN 53
J 2
(1290 2610);
DISPLAY 0.617021 (1290 2610);
PAINT ORANGE (1290 2610);
FORCEPROP 2 LASTPIN (1300 2550) $PN 55
J 2
(1290 2560);
DISPLAY 0.617021 (1290 2560);
PAINT ORANGE (1290 2560);
FORCEPROP 2 LASTPIN (1300 2500) $PN 57
J 2
(1290 2510);
DISPLAY 0.617021 (1290 2510);
PAINT ORANGE (1290 2510);
FORCEPROP 2 LASTPIN (1300 2450) $PN 94
J 2
(1290 2460);
DISPLAY 0.617021 (1290 2460);
PAINT ORANGE (1290 2460);
FORCEPROP 2 LASTPIN (1300 2400) $PN 96
J 2
(1290 2410);
DISPLAY 0.617021 (1290 2410);
PAINT ORANGE (1290 2410);
FORCEPROP 2 LASTPIN (1300 2350) $PN 98
J 2
(1290 2360);
DISPLAY 0.617021 (1290 2360);
PAINT ORANGE (1290 2360);
FORCEPROP 2 LASTPIN (1300 2300) $PN 101
J 2
(1290 2310);
DISPLAY 0.617021 (1290 2310);
PAINT ORANGE (1290 2310);
FORCEPROP 2 LASTPIN (1300 2250) $PN 103
J 2
(1290 2260);
DISPLAY 0.617021 (1290 2260);
PAINT ORANGE (1290 2260);
FORCEPROP 2 LASTPIN (1300 2200) $PN 105
J 2
(1290 2210);
DISPLAY 0.617021 (1290 2210);
PAINT ORANGE (1290 2210);
FORCEPROP 2 LASTPIN (1300 2150) $PN 107
J 2
(1290 2160);
DISPLAY 0.617021 (1290 2160);
PAINT ORANGE (1290 2160);
FORCEPROP 2 LASTPIN (1300 2100) $PN 109
J 2
(1290 2110);
DISPLAY 0.617021 (1290 2110);
PAINT ORANGE (1290 2110);
FORCEPROP 2 LASTPIN (1300 2050) $PN 112
J 2
(1290 2060);
DISPLAY 0.617021 (1290 2060);
PAINT ORANGE (1290 2060);
FORCEPROP 2 LASTPIN (1300 2000) $PN 114
J 2
(1290 2010);
DISPLAY 0.617021 (1290 2010);
PAINT ORANGE (1290 2010);
FORCEPROP 2 LASTPIN (1300 1900) $PN 118
J 2
(1290 1910);
DISPLAY 0.617021 (1290 1910);
PAINT ORANGE (1290 1910);
FORCEPROP 2 LASTPIN (1300 1850) $PN 120
J 2
(1290 1860);
DISPLAY 0.617021 (1290 1860);
PAINT ORANGE (1290 1860);
FORCEPROP 2 LASTPIN (1300 1800) $PN 123
J 2
(1290 1810);
DISPLAY 0.617021 (1290 1810);
PAINT ORANGE (1290 1810);
FORCEPROP 2 LASTPIN (1300 1750) $PN 125
J 2
(1290 1760);
DISPLAY 0.617021 (1290 1760);
PAINT ORANGE (1290 1760);
FORCEPROP 2 LASTPIN (1300 1700) $PN 127
J 2
(1290 1710);
DISPLAY 0.617021 (1290 1710);
PAINT ORANGE (1290 1710);
FORCEPROP 2 LASTPIN (1300 1650) $PN 129
J 2
(1290 1660);
DISPLAY 0.617021 (1290 1660);
PAINT ORANGE (1290 1660);
FORCEPROP 2 LASTPIN (1300 1600) $PN 131
J 2
(1290 1610);
DISPLAY 0.617021 (1290 1610);
PAINT ORANGE (1290 1610);
FORCEPROP 2 LASTPIN (1300 1550) $PN 134
J 2
(1290 1560);
DISPLAY 0.617021 (1290 1560);
PAINT ORANGE (1290 1560);
FORCEPROP 2 LASTPIN (1300 1450) $PN 138
J 2
(1290 1460);
DISPLAY 0.617021 (1290 1460);
PAINT ORANGE (1290 1460);
FORCEPROP 2 LASTPIN (2300 3750) $PN 147
J 0
(2310 3760);
DISPLAY 0.617021 (2310 3760);
PAINT ORANGE (2310 3760);
FORCEPROP 2 LASTPIN (2300 3700) $PN 149
J 0
(2310 3710);
DISPLAY 0.617021 (2310 3710);
PAINT ORANGE (2310 3710);
FORCEPROP 2 LASTPIN (2300 3650) $PN 151
J 0
(2310 3660);
DISPLAY 0.617021 (2310 3660);
PAINT ORANGE (2310 3660);
FORCEPROP 2 LASTPIN (2300 3600) $PN 154
J 0
(2310 3610);
DISPLAY 0.617021 (2310 3610);
PAINT ORANGE (2310 3610);
FORCEPROP 2 LASTPIN (2300 3550) $PN 156
J 0
(2310 3560);
DISPLAY 0.617021 (2310 3560);
PAINT ORANGE (2310 3560);
FORCEPROP 2 LASTPIN (2300 3500) $PN 158
J 0
(2310 3510);
DISPLAY 0.617021 (2310 3510);
PAINT ORANGE (2310 3510);
FORCEPROP 2 LASTPIN (2300 3450) $PN 160
J 0
(2310 3460);
DISPLAY 0.617021 (2310 3460);
PAINT ORANGE (2310 3460);
FORCEPROP 2 LASTPIN (2300 3400) $PN 162
J 0
(2310 3410);
DISPLAY 0.617021 (2310 3410);
PAINT ORANGE (2310 3410);
FORCEPROP 2 LASTPIN (2300 3350) $PN 165
J 0
(2310 3360);
DISPLAY 0.617021 (2310 3360);
PAINT ORANGE (2310 3360);
FORCEPROP 2 LASTPIN (2300 3300) $PN 167
J 0
(2310 3310);
DISPLAY 0.617021 (2310 3310);
PAINT ORANGE (2310 3310);
FORCEPROP 2 LASTPIN (2300 3250) $PN 169
J 0
(2310 3260);
DISPLAY 0.617021 (2310 3260);
PAINT ORANGE (2310 3260);
FORCEPROP 2 LASTPIN (2300 3200) $PN 171
J 0
(2310 3210);
DISPLAY 0.617021 (2310 3210);
PAINT ORANGE (2310 3210);
FORCEPROP 2 LASTPIN (2300 3150) $PN 173
J 0
(2310 3160);
DISPLAY 0.617021 (2310 3160);
PAINT ORANGE (2310 3160);
FORCEPROP 2 LASTPIN (2300 3100) $PN 176
J 0
(2310 3110);
DISPLAY 0.617021 (2310 3110);
PAINT ORANGE (2310 3110);
FORCEPROP 2 LASTPIN (2300 3050) $PN 178
J 0
(2310 3060);
DISPLAY 0.617021 (2310 3060);
PAINT ORANGE (2310 3060);
FORCEPROP 2 LASTPIN (2300 3000) $PN 180
J 0
(2310 3010);
DISPLAY 0.617021 (2310 3010);
PAINT ORANGE (2310 3010);
FORCEPROP 2 LASTPIN (2300 2950) $PN 182
J 0
(2310 2960);
DISPLAY 0.617021 (2310 2960);
PAINT ORANGE (2310 2960);
FORCEPROP 2 LASTPIN (2300 2900) $PN 184
J 0
(2310 2910);
DISPLAY 0.617021 (2310 2910);
PAINT ORANGE (2310 2910);
FORCEPROP 2 LASTPIN (2300 2850) $PN 187
J 0
(2310 2860);
DISPLAY 0.617021 (2310 2860);
PAINT ORANGE (2310 2860);
FORCEPROP 2 LASTPIN (2300 2800) $PN 189
J 0
(2310 2810);
DISPLAY 0.617021 (2310 2810);
PAINT ORANGE (2310 2810);
FORCEPROP 2 LASTPIN (2300 2750) $PN 191
J 0
(2310 2760);
DISPLAY 0.617021 (2310 2760);
PAINT ORANGE (2310 2760);
FORCEPROP 2 LASTPIN (2300 2700) $PN 193
J 0
(2310 2710);
DISPLAY 0.617021 (2310 2710);
PAINT ORANGE (2310 2710);
FORCEPROP 2 LASTPIN (2300 2650) $PN 195
J 0
(2310 2660);
DISPLAY 0.617021 (2310 2660);
PAINT ORANGE (2310 2660);
FORCEPROP 2 LASTPIN (2300 2600) $PN 198
J 0
(2310 2610);
DISPLAY 0.617021 (2310 2610);
PAINT ORANGE (2310 2610);
FORCEPROP 2 LASTPIN (2300 2550) $PN 200
J 0
(2310 2560);
DISPLAY 0.617021 (2310 2560);
PAINT ORANGE (2310 2560);
FORCEPROP 2 LASTPIN (2300 2500) $PN 202
J 0
(2310 2510);
DISPLAY 0.617021 (2310 2510);
PAINT ORANGE (2310 2510);
FORCEPROP 2 LASTPIN (2300 2450) $PN 239
J 0
(2310 2460);
DISPLAY 0.617021 (2310 2460);
PAINT ORANGE (2310 2460);
FORCEPROP 2 LASTPIN (2300 2400) $PN 241
J 0
(2310 2410);
DISPLAY 0.617021 (2310 2410);
PAINT ORANGE (2310 2410);
FORCEPROP 2 LASTPIN (2300 2350) $PN 243
J 0
(2310 2360);
DISPLAY 0.617021 (2310 2360);
PAINT ORANGE (2310 2360);
FORCEPROP 2 LASTPIN (2300 2300) $PN 246
J 0
(2310 2310);
DISPLAY 0.617021 (2310 2310);
PAINT ORANGE (2310 2310);
FORCEPROP 2 LASTPIN (2300 2250) $PN 248
J 0
(2310 2260);
DISPLAY 0.617021 (2310 2260);
PAINT ORANGE (2310 2260);
FORCEPROP 2 LASTPIN (2300 2200) $PN 250
J 0
(2310 2210);
DISPLAY 0.617021 (2310 2210);
PAINT ORANGE (2310 2210);
FORCEPROP 2 LASTPIN (2300 2150) $PN 252
J 0
(2310 2160);
DISPLAY 0.617021 (2310 2160);
PAINT ORANGE (2310 2160);
FORCEPROP 2 LASTPIN (2300 2100) $PN 254
J 0
(2310 2110);
DISPLAY 0.617021 (2310 2110);
PAINT ORANGE (2310 2110);
FORCEPROP 2 LASTPIN (2300 2050) $PN 257
J 0
(2310 2060);
DISPLAY 0.617021 (2310 2060);
PAINT ORANGE (2310 2060);
FORCEPROP 2 LASTPIN (2300 2000) $PN 259
J 0
(2310 2010);
DISPLAY 0.617021 (2310 2010);
PAINT ORANGE (2310 2010);
FORCEPROP 2 LASTPIN (2300 1950) $PN 261
J 0
(2310 1960);
DISPLAY 0.617021 (2310 1960);
PAINT ORANGE (2310 1960);
FORCEPROP 2 LASTPIN (2300 1900) $PN 263
J 0
(2310 1910);
DISPLAY 0.617021 (2310 1910);
PAINT ORANGE (2310 1910);
FORCEPROP 2 LASTPIN (2300 1850) $PN 265
J 0
(2310 1860);
DISPLAY 0.617021 (2310 1860);
PAINT ORANGE (2310 1860);
FORCEPROP 2 LASTPIN (2300 1800) $PN 268
J 0
(2310 1810);
DISPLAY 0.617021 (2310 1810);
PAINT ORANGE (2310 1810);
FORCEPROP 2 LASTPIN (2300 1750) $PN 270
J 0
(2310 1760);
DISPLAY 0.617021 (2310 1760);
PAINT ORANGE (2310 1760);
FORCEPROP 2 LASTPIN (2300 1700) $PN 272
J 0
(2310 1710);
DISPLAY 0.617021 (2310 1710);
PAINT ORANGE (2310 1710);
FORCEPROP 2 LASTPIN (2300 1650) $PN 274
J 0
(2310 1660);
DISPLAY 0.617021 (2310 1660);
PAINT ORANGE (2310 1660);
FORCEPROP 2 LASTPIN (2300 1600) $PN 276
J 0
(2310 1610);
DISPLAY 0.617021 (2310 1610);
PAINT ORANGE (2310 1610);
FORCEPROP 2 LASTPIN (2300 1550) $PN 279
J 0
(2310 1560);
DISPLAY 0.617021 (2310 1560);
PAINT ORANGE (2310 1560);
FORCEPROP 2 LASTPIN (2300 1500) $PN 281
J 0
(2310 1510);
DISPLAY 0.617021 (2310 1510);
PAINT ORANGE (2310 1510);
FORCEPROP 2 LASTPIN (2300 1450) $PN 283
J 0
(2310 1460);
DISPLAY 0.617021 (2310 1460);
PAINT ORANGE (2310 1460);
FORCEPROP 2 LASTPIN (1300 1950) $PN 116
J 2
(1290 1960);
DISPLAY 0.617021 (1290 1960);
PAINT ORANGE (1290 1960);
FORCEPROP 2 LASTPIN (1300 1500) $PN 136
J 2
(1290 1510);
DISPLAY 0.617021 (1290 1510);
PAINT ORANGE (1290 1510);
FORCEPROP 1 LAST PACK_TYPE PIP
J 0
(1350 4050);
PAINT SKYBLUE (1350 4050);
DISPLAY INVISIBLE (1350 4050);
FORCEPROP 2 LAST BOM_COST MEM
J 0
(1800 2600);
PAINT ORANGE (1800 2600);
DISPLAY INVISIBLE (1800 2600);
FORCEPROP 2 LAST CDS_LIB mstr_sconn
J 0
(1800 2600);
PAINT ORANGE (1800 2600);
DISPLAY INVISIBLE (1800 2600);
FORCEPROP 2 LAST SEC_TYPE PIP
J 0
(1350 4050);
DISPLAY 1.021277 (1350 4050);
PAINT ORANGE (1350 4050);
DISPLAY INVISIBLE (1350 4050);
FORCEPROP 2 LAST SEC 3
J 0
(1350 4050);
DISPLAY 0.680851 (1350 4050);
PAINT MONO (1350 4050);
DISPLAY INVISIBLE (1350 4050);
FORCEPROP 2 LAST CDS_LOCATION J4G2
J 0
(1350 4000);
DISPLAY 0.617021 (1350 4000);
PAINT AQUA (1350 4000);
DISPLAY INVISIBLE (1350 4000);
FORCEPROP 1 LAST PATH I43
J 0
(1800 3950);
PAINT GREEN (1800 3950);
DISPLAY INVISIBLE (1800 3950);
FORCEPROP 2 LAST ROOM DDR4_CH_B
J 0
(1800 2600);
PAINT ORANGE (1800 2600);
DISPLAY INVISIBLE (1800 2600);
FORCEADD GND..1
R 2
(1100 1300);
FORCEPROP 3 LASTPIN (1100 1350) SIG_NAME GND\g
J 0
(1110 1360);
DISPLAY 0.659574 (1110 1360);
PAINT MONO (1110 1360);
DISPLAY INVISIBLE (1110 1360);
FORCEPROP 1 LAST VOLTAGE 0
J 0
(1100 1300);
PAINT SKYBLUE (1100 1300);
DISPLAY INVISIBLE (1100 1300);
FORCEPROP 2 LAST BOM_COST MEM
J 0
(1100 1305);
PAINT ORANGE (1100 1305);
DISPLAY INVISIBLE (1100 1305);
FORCEPROP 2 LAST CDS_LIB mstr_symbols
J 0
(1100 1300);
DISPLAY 0.787234 (1100 1300);
PAINT MONO (1100 1300);
DISPLAY INVISIBLE (1100 1300);
FORCEPROP 1 LAST SIZE 1B
J 2
(1025 1250);
DISPLAY 1.170213 (1025 1250);
PAINT GREEN (1025 1250);
DISPLAY INVISIBLE (1025 1250);
FORCEPROP 1 LAST BODY_TYPE PLUMBING
J 2
(1145 1257);
DISPLAY 0.340426 (1145 1257);
PAINT GREEN (1145 1257);
DISPLAY INVISIBLE (1145 1257);
FORCEPROP 1 LAST PATH I44
J 2
(1025 1300);
DISPLAY 0.936170 (1025 1300);
PAINT GREEN (1025 1300);
DISPLAY INVISIBLE (1025 1300);
FORCEPROP 2 LAST ROOM DDR4_CH_A
J 0
(1100 1305);
PAINT ORANGE (1100 1305);
DISPLAY INVISIBLE (1100 1305);
FORCEPROP 1 LAST HDL_POWER GND
J 2
(1100 1450);
DISPLAY 0.553191 (1100 1450);
PAINT GREEN (1100 1450);
DISPLAY INVISIBLE (1100 1450);
FORCEADD OFFPAGE..3
(-1150 4650);
FORCEPROP 2 LAST $XR1 46 
J 0
(-846 4650);
DISPLAY 0.638298 (-846 4650);
PAINT MONO (-846 4650);
FORCEPROP 2 LAST $XR0 24 
J 0
(-936 4650);
DISPLAY 0.638298 (-936 4650);
PAINT MONO (-936 4650);
FORCEPROP 2 LAST CDS_LIB mstr_standard
J 0
(-1150 4650);
DISPLAY 0.787234 (-1150 4650);
PAINT MONO (-1150 4650);
DISPLAY INVISIBLE (-1150 4650);
FORCEPROP 1 LAST OFFPAGE TRUE
J 0
(-825 4525);
DISPLAY 0.936170 (-825 4525);
PAINT GREEN (-825 4525);
DISPLAY INVISIBLE (-825 4525);
FORCEPROP 1 LAST COMMENT_BODY TRUE
J 0
(-1200 4550);
DISPLAY 0.936170 (-1200 4550);
PAINT GREEN (-1200 4550);
DISPLAY INVISIBLE (-1200 4550);
FORCEPROP 2 LAST PATH I45
J 0
(-950 4725);
DISPLAY 0.787234 (-950 4725);
PAINT MONO (-950 4725);
DISPLAY INVISIBLE (-950 4725);
FORCEADD TAP..6
R 2
(-1700 4600);
FORCEPROP 3 LASTPIN (-1750 4600) SIG_NAME M_B_DQ<62>
J 0
(-1740 4610);
DISPLAY 0.659574 (-1740 4610);
PAINT MONO (-1740 4610);
DISPLAY INVISIBLE (-1740 4610);
FORCEPROP 1 LASTPIN (-1750 4600) BN 62
J 2
(-1700 4610);
DISPLAY 0.617021 (-1700 4610);
PAINT PINK (-1700 4610);
FORCEPROP 2 LAST CDS_LIB mstr_standard
J 2
(-1700 4600);
DISPLAY 0.787234 (-1700 4600);
PAINT MONO (-1700 4600);
DISPLAY INVISIBLE (-1700 4600);
FORCEPROP 1 LAST BODY_TYPE PLUMBING
J 2
(-1700 4550);
DISPLAY 1.234043 (-1700 4550);
PAINT GREEN (-1700 4550);
DISPLAY INVISIBLE (-1700 4550);
FORCEPROP 1 LAST HDL_TAP TRUE
J 2
(-2025 4475);
DISPLAY 1.234043 (-2025 4475);
PAINT GREEN (-2025 4475);
DISPLAY INVISIBLE (-2025 4475);
FORCEPROP 1 LAST PATH I46
J 2
(-1700 4600);
DISPLAY 0.936170 (-1700 4600);
PAINT GREEN (-1700 4600);
DISPLAY INVISIBLE (-1700 4600);
FORCEADD TAP..6
R 2
(-1700 4550);
FORCEPROP 3 LASTPIN (-1750 4550) SIG_NAME M_B_DQ<63>
J 0
(-1740 4560);
DISPLAY 0.659574 (-1740 4560);
PAINT MONO (-1740 4560);
DISPLAY INVISIBLE (-1740 4560);
FORCEPROP 1 LASTPIN (-1750 4550) BN 63
J 2
(-1700 4560);
DISPLAY 0.617021 (-1700 4560);
PAINT PINK (-1700 4560);
FORCEPROP 2 LAST CDS_LIB mstr_standard
J 2
(-1700 4550);
DISPLAY 0.787234 (-1700 4550);
PAINT MONO (-1700 4550);
DISPLAY INVISIBLE (-1700 4550);
FORCEPROP 1 LAST BODY_TYPE PLUMBING
J 2
(-1700 4500);
DISPLAY 1.234043 (-1700 4500);
PAINT GREEN (-1700 4500);
DISPLAY INVISIBLE (-1700 4500);
FORCEPROP 1 LAST HDL_TAP TRUE
J 2
(-2025 4425);
DISPLAY 1.234043 (-2025 4425);
PAINT GREEN (-2025 4425);
DISPLAY INVISIBLE (-2025 4425);
FORCEPROP 1 LAST PATH I47
J 2
(-1700 4550);
DISPLAY 0.936170 (-1700 4550);
PAINT GREEN (-1700 4550);
DISPLAY INVISIBLE (-1700 4550);
FORCEADD TAP..6
R 2
(-1700 4400);
FORCEPROP 3 LASTPIN (-1750 4400) SIG_NAME M_B_DQ<58>
J 0
(-1740 4410);
DISPLAY 0.659574 (-1740 4410);
PAINT MONO (-1740 4410);
DISPLAY INVISIBLE (-1740 4410);
FORCEPROP 1 LASTPIN (-1750 4400) BN 58
J 2
(-1700 4410);
DISPLAY 0.617021 (-1700 4410);
PAINT PINK (-1700 4410);
FORCEPROP 2 LAST CDS_LIB mstr_standard
J 2
(-1700 4400);
DISPLAY 0.787234 (-1700 4400);
PAINT MONO (-1700 4400);
DISPLAY INVISIBLE (-1700 4400);
FORCEPROP 1 LAST BODY_TYPE PLUMBING
J 2
(-1700 4350);
DISPLAY 1.234043 (-1700 4350);
PAINT GREEN (-1700 4350);
DISPLAY INVISIBLE (-1700 4350);
FORCEPROP 1 LAST HDL_TAP TRUE
J 2
(-2025 4275);
DISPLAY 1.234043 (-2025 4275);
PAINT GREEN (-2025 4275);
DISPLAY INVISIBLE (-2025 4275);
FORCEPROP 1 LAST PATH I48
J 2
(-1700 4400);
DISPLAY 0.936170 (-1700 4400);
PAINT GREEN (-1700 4400);
DISPLAY INVISIBLE (-1700 4400);
FORCEADD TAP..6
R 2
(-1700 4450);
FORCEPROP 3 LASTPIN (-1750 4450) SIG_NAME M_B_DQ<61>
J 0
(-1740 4460);
DISPLAY 0.659574 (-1740 4460);
PAINT MONO (-1740 4460);
DISPLAY INVISIBLE (-1740 4460);
FORCEPROP 1 LASTPIN (-1750 4450) BN 61
J 2
(-1700 4460);
DISPLAY 0.617021 (-1700 4460);
PAINT PINK (-1700 4460);
FORCEPROP 2 LAST CDS_LIB mstr_standard
J 2
(-1700 4450);
DISPLAY 0.787234 (-1700 4450);
PAINT MONO (-1700 4450);
DISPLAY INVISIBLE (-1700 4450);
FORCEPROP 1 LAST BODY_TYPE PLUMBING
J 2
(-1700 4400);
DISPLAY 1.234043 (-1700 4400);
PAINT GREEN (-1700 4400);
DISPLAY INVISIBLE (-1700 4400);
FORCEPROP 1 LAST HDL_TAP TRUE
J 2
(-2025 4325);
DISPLAY 1.234043 (-2025 4325);
PAINT GREEN (-2025 4325);
DISPLAY INVISIBLE (-2025 4325);
FORCEPROP 1 LAST PATH I49
J 2
(-1700 4450);
DISPLAY 0.936170 (-1700 4450);
PAINT GREEN (-1700 4450);
DISPLAY INVISIBLE (-1700 4450);
FORCEADD TAP..6
R 2
(700 5050);
FORCEPROP 3 LASTPIN (650 5050) SIG_NAME M_B_DQS_DP<16>
J 0
(660 5060);
DISPLAY 0.659574 (660 5060);
PAINT MONO (660 5060);
DISPLAY INVISIBLE (660 5060);
FORCEPROP 1 LASTPIN (650 5050) BN 16
J 2
(700 5060);
DISPLAY 0.617021 (700 5060);
PAINT PINK (700 5060);
FORCEPROP 2 LAST CDS_LIB mstr_standard
J 0
(700 5050);
DISPLAY 0.787234 (700 5050);
PAINT MONO (700 5050);
DISPLAY INVISIBLE (700 5050);
FORCEPROP 1 LAST BODY_TYPE PLUMBING
J 2
(700 5000);
DISPLAY 1.234043 (700 5000);
PAINT GREEN (700 5000);
DISPLAY INVISIBLE (700 5000);
FORCEPROP 1 LAST HDL_TAP TRUE
J 2
(375 4925);
DISPLAY 1.234043 (375 4925);
PAINT GREEN (375 4925);
DISPLAY INVISIBLE (375 4925);
FORCEPROP 1 LAST PATH I5
J 2
(700 5050);
DISPLAY 0.936170 (700 5050);
PAINT GREEN (700 5050);
DISPLAY INVISIBLE (700 5050);
FORCEADD TAP..6
R 2
(-1700 4500);
FORCEPROP 3 LASTPIN (-1750 4500) SIG_NAME M_B_DQ<60>
J 0
(-1740 4510);
DISPLAY 0.659574 (-1740 4510);
PAINT MONO (-1740 4510);
DISPLAY INVISIBLE (-1740 4510);
FORCEPROP 1 LASTPIN (-1750 4500) BN 60
J 2
(-1700 4510);
DISPLAY 0.617021 (-1700 4510);
PAINT PINK (-1700 4510);
FORCEPROP 2 LAST CDS_LIB mstr_standard
J 2
(-1700 4500);
DISPLAY 0.787234 (-1700 4500);
PAINT MONO (-1700 4500);
DISPLAY INVISIBLE (-1700 4500);
FORCEPROP 1 LAST BODY_TYPE PLUMBING
J 2
(-1700 4450);
DISPLAY 1.234043 (-1700 4450);
PAINT GREEN (-1700 4450);
DISPLAY INVISIBLE (-1700 4450);
FORCEPROP 1 LAST HDL_TAP TRUE
J 2
(-2025 4375);
DISPLAY 1.234043 (-2025 4375);
PAINT GREEN (-2025 4375);
DISPLAY INVISIBLE (-2025 4375);
FORCEPROP 1 LAST PATH I50
J 2
(-1700 4500);
DISPLAY 0.936170 (-1700 4500);
PAINT GREEN (-1700 4500);
DISPLAY INVISIBLE (-1700 4500);
FORCEADD TAP..6
R 2
(-1700 4300);
FORCEPROP 3 LASTPIN (-1750 4300) SIG_NAME M_B_DQ<56>
J 0
(-1740 4310);
DISPLAY 0.659574 (-1740 4310);
PAINT MONO (-1740 4310);
DISPLAY INVISIBLE (-1740 4310);
FORCEPROP 1 LASTPIN (-1750 4300) BN 56
J 2
(-1700 4310);
DISPLAY 0.617021 (-1700 4310);
PAINT PINK (-1700 4310);
FORCEPROP 2 LAST CDS_LIB mstr_standard
J 2
(-1700 4300);
DISPLAY 0.787234 (-1700 4300);
PAINT MONO (-1700 4300);
DISPLAY INVISIBLE (-1700 4300);
FORCEPROP 1 LAST BODY_TYPE PLUMBING
J 2
(-1700 4250);
DISPLAY 1.234043 (-1700 4250);
PAINT GREEN (-1700 4250);
DISPLAY INVISIBLE (-1700 4250);
FORCEPROP 1 LAST HDL_TAP TRUE
J 2
(-2025 4175);
DISPLAY 1.234043 (-2025 4175);
PAINT GREEN (-2025 4175);
DISPLAY INVISIBLE (-2025 4175);
FORCEPROP 1 LAST PATH I51
J 2
(-1700 4300);
DISPLAY 0.936170 (-1700 4300);
PAINT GREEN (-1700 4300);
DISPLAY INVISIBLE (-1700 4300);
FORCEADD TAP..6
R 2
(-1700 4350);
FORCEPROP 3 LASTPIN (-1750 4350) SIG_NAME M_B_DQ<59>
J 0
(-1740 4360);
DISPLAY 0.659574 (-1740 4360);
PAINT MONO (-1740 4360);
DISPLAY INVISIBLE (-1740 4360);
FORCEPROP 1 LASTPIN (-1750 4350) BN 59
J 2
(-1700 4360);
DISPLAY 0.617021 (-1700 4360);
PAINT PINK (-1700 4360);
FORCEPROP 2 LAST CDS_LIB mstr_standard
J 2
(-1700 4350);
DISPLAY 0.787234 (-1700 4350);
PAINT MONO (-1700 4350);
DISPLAY INVISIBLE (-1700 4350);
FORCEPROP 1 LAST BODY_TYPE PLUMBING
J 2
(-1700 4300);
DISPLAY 1.234043 (-1700 4300);
PAINT GREEN (-1700 4300);
DISPLAY INVISIBLE (-1700 4300);
FORCEPROP 1 LAST HDL_TAP TRUE
J 2
(-2025 4225);
DISPLAY 1.234043 (-2025 4225);
PAINT GREEN (-2025 4225);
DISPLAY INVISIBLE (-2025 4225);
FORCEPROP 1 LAST PATH I52
J 2
(-1700 4350);
DISPLAY 0.936170 (-1700 4350);
PAINT GREEN (-1700 4350);
DISPLAY INVISIBLE (-1700 4350);
FORCEADD TAP..6
R 2
(-1700 4150);
FORCEPROP 3 LASTPIN (-1750 4150) SIG_NAME M_B_DQ<55>
J 0
(-1740 4160);
DISPLAY 0.659574 (-1740 4160);
PAINT MONO (-1740 4160);
DISPLAY INVISIBLE (-1740 4160);
FORCEPROP 1 LASTPIN (-1750 4150) BN 55
J 2
(-1700 4160);
DISPLAY 0.617021 (-1700 4160);
PAINT PINK (-1700 4160);
FORCEPROP 2 LAST CDS_LIB mstr_standard
J 2
(-1700 4150);
DISPLAY 0.787234 (-1700 4150);
PAINT MONO (-1700 4150);
DISPLAY INVISIBLE (-1700 4150);
FORCEPROP 1 LAST BODY_TYPE PLUMBING
J 2
(-1700 4100);
DISPLAY 1.234043 (-1700 4100);
PAINT GREEN (-1700 4100);
DISPLAY INVISIBLE (-1700 4100);
FORCEPROP 1 LAST HDL_TAP TRUE
J 2
(-2025 4025);
DISPLAY 1.234043 (-2025 4025);
PAINT GREEN (-2025 4025);
DISPLAY INVISIBLE (-2025 4025);
FORCEPROP 1 LAST PATH I53
J 2
(-1700 4150);
DISPLAY 0.936170 (-1700 4150);
PAINT GREEN (-1700 4150);
DISPLAY INVISIBLE (-1700 4150);
FORCEADD TAP..6
R 2
(-1700 4200);
FORCEPROP 3 LASTPIN (-1750 4200) SIG_NAME M_B_DQ<54>
J 0
(-1740 4210);
DISPLAY 0.659574 (-1740 4210);
PAINT MONO (-1740 4210);
DISPLAY INVISIBLE (-1740 4210);
FORCEPROP 1 LASTPIN (-1750 4200) BN 54
J 2
(-1700 4210);
DISPLAY 0.617021 (-1700 4210);
PAINT PINK (-1700 4210);
FORCEPROP 2 LAST CDS_LIB mstr_standard
J 2
(-1700 4200);
DISPLAY 0.787234 (-1700 4200);
PAINT MONO (-1700 4200);
DISPLAY INVISIBLE (-1700 4200);
FORCEPROP 1 LAST BODY_TYPE PLUMBING
J 2
(-1700 4150);
DISPLAY 1.234043 (-1700 4150);
PAINT GREEN (-1700 4150);
DISPLAY INVISIBLE (-1700 4150);
FORCEPROP 1 LAST HDL_TAP TRUE
J 2
(-2025 4075);
DISPLAY 1.234043 (-2025 4075);
PAINT GREEN (-2025 4075);
DISPLAY INVISIBLE (-2025 4075);
FORCEPROP 1 LAST PATH I54
J 2
(-1700 4200);
DISPLAY 0.936170 (-1700 4200);
PAINT GREEN (-1700 4200);
DISPLAY INVISIBLE (-1700 4200);
FORCEADD TAP..6
R 2
(-1700 4250);
FORCEPROP 3 LASTPIN (-1750 4250) SIG_NAME M_B_DQ<57>
J 0
(-1740 4260);
DISPLAY 0.659574 (-1740 4260);
PAINT MONO (-1740 4260);
DISPLAY INVISIBLE (-1740 4260);
FORCEPROP 1 LASTPIN (-1750 4250) BN 57
J 2
(-1700 4260);
DISPLAY 0.617021 (-1700 4260);
PAINT PINK (-1700 4260);
FORCEPROP 2 LAST CDS_LIB mstr_standard
J 2
(-1700 4250);
DISPLAY 0.787234 (-1700 4250);
PAINT MONO (-1700 4250);
DISPLAY INVISIBLE (-1700 4250);
FORCEPROP 1 LAST BODY_TYPE PLUMBING
J 2
(-1700 4200);
DISPLAY 1.234043 (-1700 4200);
PAINT GREEN (-1700 4200);
DISPLAY INVISIBLE (-1700 4200);
FORCEPROP 1 LAST HDL_TAP TRUE
J 2
(-2025 4125);
DISPLAY 1.234043 (-2025 4125);
PAINT GREEN (-2025 4125);
DISPLAY INVISIBLE (-2025 4125);
FORCEPROP 1 LAST PATH I55
J 2
(-1700 4250);
DISPLAY 0.936170 (-1700 4250);
PAINT GREEN (-1700 4250);
DISPLAY INVISIBLE (-1700 4250);
FORCEADD TAP..6
R 2
(-1700 4050);
FORCEPROP 3 LASTPIN (-1750 4050) SIG_NAME M_B_DQ<53>
J 0
(-1740 4060);
DISPLAY 0.659574 (-1740 4060);
PAINT MONO (-1740 4060);
DISPLAY INVISIBLE (-1740 4060);
FORCEPROP 1 LASTPIN (-1750 4050) BN 53
J 2
(-1700 4060);
DISPLAY 0.617021 (-1700 4060);
PAINT PINK (-1700 4060);
FORCEPROP 2 LAST CDS_LIB mstr_standard
J 2
(-1700 4050);
DISPLAY 0.787234 (-1700 4050);
PAINT MONO (-1700 4050);
DISPLAY INVISIBLE (-1700 4050);
FORCEPROP 1 LAST BODY_TYPE PLUMBING
J 2
(-1700 4000);
DISPLAY 1.234043 (-1700 4000);
PAINT GREEN (-1700 4000);
DISPLAY INVISIBLE (-1700 4000);
FORCEPROP 1 LAST HDL_TAP TRUE
J 2
(-2025 3925);
DISPLAY 1.234043 (-2025 3925);
PAINT GREEN (-2025 3925);
DISPLAY INVISIBLE (-2025 3925);
FORCEPROP 1 LAST PATH I56
J 2
(-1700 4050);
DISPLAY 0.936170 (-1700 4050);
PAINT GREEN (-1700 4050);
DISPLAY INVISIBLE (-1700 4050);
FORCEADD TAP..6
R 2
(-1700 4100);
FORCEPROP 3 LASTPIN (-1750 4100) SIG_NAME M_B_DQ<52>
J 0
(-1740 4110);
DISPLAY 0.659574 (-1740 4110);
PAINT MONO (-1740 4110);
DISPLAY INVISIBLE (-1740 4110);
FORCEPROP 1 LASTPIN (-1750 4100) BN 52
J 2
(-1700 4110);
DISPLAY 0.617021 (-1700 4110);
PAINT PINK (-1700 4110);
FORCEPROP 2 LAST CDS_LIB mstr_standard
J 2
(-1700 4100);
DISPLAY 0.787234 (-1700 4100);
PAINT MONO (-1700 4100);
DISPLAY INVISIBLE (-1700 4100);
FORCEPROP 1 LAST BODY_TYPE PLUMBING
J 2
(-1700 4050);
DISPLAY 1.234043 (-1700 4050);
PAINT GREEN (-1700 4050);
DISPLAY INVISIBLE (-1700 4050);
FORCEPROP 1 LAST HDL_TAP TRUE
J 2
(-2025 3975);
DISPLAY 1.234043 (-2025 3975);
PAINT GREEN (-2025 3975);
DISPLAY INVISIBLE (-2025 3975);
FORCEPROP 1 LAST PATH I57
J 2
(-1700 4100);
DISPLAY 0.936170 (-1700 4100);
PAINT GREEN (-1700 4100);
DISPLAY INVISIBLE (-1700 4100);
FORCEADD TAP..6
R 2
(-1700 4000);
FORCEPROP 3 LASTPIN (-1750 4000) SIG_NAME M_B_DQ<50>
J 0
(-1740 4010);
DISPLAY 0.659574 (-1740 4010);
PAINT MONO (-1740 4010);
DISPLAY INVISIBLE (-1740 4010);
FORCEPROP 1 LASTPIN (-1750 4000) BN 50
J 2
(-1700 4010);
DISPLAY 0.617021 (-1700 4010);
PAINT PINK (-1700 4010);
FORCEPROP 2 LAST CDS_LIB mstr_standard
J 2
(-1700 4000);
DISPLAY 0.787234 (-1700 4000);
PAINT MONO (-1700 4000);
DISPLAY INVISIBLE (-1700 4000);
FORCEPROP 1 LAST BODY_TYPE PLUMBING
J 2
(-1700 3950);
DISPLAY 1.234043 (-1700 3950);
PAINT GREEN (-1700 3950);
DISPLAY INVISIBLE (-1700 3950);
FORCEPROP 1 LAST HDL_TAP TRUE
J 2
(-2025 3875);
DISPLAY 1.234043 (-2025 3875);
PAINT GREEN (-2025 3875);
DISPLAY INVISIBLE (-2025 3875);
FORCEPROP 1 LAST PATH I58
J 2
(-1700 4000);
DISPLAY 0.936170 (-1700 4000);
PAINT GREEN (-1700 4000);
DISPLAY INVISIBLE (-1700 4000);
FORCEADD TAP..6
R 2
(-1700 3950);
FORCEPROP 3 LASTPIN (-1750 3950) SIG_NAME M_B_DQ<51>
J 0
(-1740 3960);
DISPLAY 0.659574 (-1740 3960);
PAINT MONO (-1740 3960);
DISPLAY INVISIBLE (-1740 3960);
FORCEPROP 1 LASTPIN (-1750 3950) BN 51
J 2
(-1700 3960);
DISPLAY 0.617021 (-1700 3960);
PAINT PINK (-1700 3960);
FORCEPROP 2 LAST CDS_LIB mstr_standard
J 2
(-1700 3950);
DISPLAY 0.787234 (-1700 3950);
PAINT MONO (-1700 3950);
DISPLAY INVISIBLE (-1700 3950);
FORCEPROP 1 LAST BODY_TYPE PLUMBING
J 2
(-1700 3900);
DISPLAY 1.234043 (-1700 3900);
PAINT GREEN (-1700 3900);
DISPLAY INVISIBLE (-1700 3900);
FORCEPROP 1 LAST HDL_TAP TRUE
J 2
(-2025 3825);
DISPLAY 1.234043 (-2025 3825);
PAINT GREEN (-2025 3825);
DISPLAY INVISIBLE (-2025 3825);
FORCEPROP 1 LAST PATH I59
J 2
(-1700 3950);
DISPLAY 0.936170 (-1700 3950);
PAINT GREEN (-1700 3950);
DISPLAY INVISIBLE (-1700 3950);
FORCEADD TAP..6
R 2
(900 4900);
FORCEPROP 3 LASTPIN (850 4900) SIG_NAME M_B_DQS_DN<15>
J 0
(860 4910);
DISPLAY 0.659574 (860 4910);
PAINT MONO (860 4910);
DISPLAY INVISIBLE (860 4910);
FORCEPROP 1 LASTPIN (850 4900) BN 15
J 2
(900 4910);
DISPLAY 0.617021 (900 4910);
PAINT PINK (900 4910);
FORCEPROP 2 LAST CDS_LIB mstr_standard
J 0
(900 4900);
DISPLAY 0.787234 (900 4900);
PAINT MONO (900 4900);
DISPLAY INVISIBLE (900 4900);
FORCEPROP 1 LAST BODY_TYPE PLUMBING
J 2
(900 4850);
DISPLAY 1.234043 (900 4850);
PAINT GREEN (900 4850);
DISPLAY INVISIBLE (900 4850);
FORCEPROP 1 LAST HDL_TAP TRUE
J 2
(575 4775);
DISPLAY 1.234043 (575 4775);
PAINT GREEN (575 4775);
DISPLAY INVISIBLE (575 4775);
FORCEPROP 1 LAST PATH I6
J 2
(900 4900);
DISPLAY 0.936170 (900 4900);
PAINT GREEN (900 4900);
DISPLAY INVISIBLE (900 4900);
FORCEADD TAP..6
R 2
(-1700 3900);
FORCEPROP 3 LASTPIN (-1750 3900) SIG_NAME M_B_DQ<48>
J 0
(-1740 3910);
DISPLAY 0.659574 (-1740 3910);
PAINT MONO (-1740 3910);
DISPLAY INVISIBLE (-1740 3910);
FORCEPROP 1 LASTPIN (-1750 3900) BN 48
J 2
(-1700 3910);
DISPLAY 0.617021 (-1700 3910);
PAINT PINK (-1700 3910);
FORCEPROP 2 LAST CDS_LIB mstr_standard
J 2
(-1700 3900);
DISPLAY 0.787234 (-1700 3900);
PAINT MONO (-1700 3900);
DISPLAY INVISIBLE (-1700 3900);
FORCEPROP 1 LAST BODY_TYPE PLUMBING
J 2
(-1700 3850);
DISPLAY 1.234043 (-1700 3850);
PAINT GREEN (-1700 3850);
DISPLAY INVISIBLE (-1700 3850);
FORCEPROP 1 LAST HDL_TAP TRUE
J 2
(-2025 3775);
DISPLAY 1.234043 (-2025 3775);
PAINT GREEN (-2025 3775);
DISPLAY INVISIBLE (-2025 3775);
FORCEPROP 1 LAST PATH I60
J 2
(-1700 3900);
DISPLAY 0.936170 (-1700 3900);
PAINT GREEN (-1700 3900);
DISPLAY INVISIBLE (-1700 3900);
FORCEADD SCONN288_H44441004..2
(0 4300);
FORCEPROP 1 LAST LOCATION J4G2
J 0
(-400 5400);
DISPLAY 0.617021 (-400 5400);
PAINT AQUA (-400 5400);
FORCEPROP 1 LAST PART_NUMBER H44441-004
J 0
(-400 3200);
DISPLAY 0.617021 (-400 3200);
PAINT BLUE (-400 3200);
FORCEPROP 1 LAST MATERIAL SCONN
J 0
(-400 5350);
DISPLAY 0.617021 (-400 5350);
PAINT SKYBLUE (-400 5350);
FORCEPROP 2 LASTPIN (450 5150) $PN 51
J 0
(460 5160);
DISPLAY 0.617021 (460 5160);
PAINT ORANGE (460 5160);
FORCEPROP 2 LASTPIN (450 5100) $PN 52
J 0
(460 5110);
DISPLAY 0.617021 (460 5110);
PAINT ORANGE (460 5110);
FORCEPROP 2 LASTPIN (450 5050) $PN 132
J 0
(460 5060);
DISPLAY 0.617021 (460 5060);
PAINT ORANGE (460 5060);
FORCEPROP 2 LASTPIN (450 5000) $PN 133
J 0
(460 5010);
DISPLAY 0.617021 (460 5010);
PAINT ORANGE (460 5010);
FORCEPROP 2 LASTPIN (450 4950) $PN 121
J 0
(460 4960);
DISPLAY 0.617021 (460 4960);
PAINT ORANGE (460 4960);
FORCEPROP 2 LASTPIN (450 4850) $PN 110
J 0
(460 4860);
DISPLAY 0.617021 (460 4860);
PAINT ORANGE (460 4860);
FORCEPROP 2 LASTPIN (450 4800) $PN 111
J 0
(460 4810);
DISPLAY 0.617021 (460 4810);
PAINT ORANGE (460 4810);
FORCEPROP 2 LASTPIN (450 4750) $PN 99
J 0
(460 4760);
DISPLAY 0.617021 (460 4760);
PAINT ORANGE (460 4760);
FORCEPROP 2 LASTPIN (450 4700) $PN 100
J 0
(460 4710);
DISPLAY 0.617021 (460 4710);
PAINT ORANGE (460 4710);
FORCEPROP 2 LASTPIN (450 4650) $PN 40
J 0
(460 4660);
DISPLAY 0.617021 (460 4660);
PAINT ORANGE (460 4660);
FORCEPROP 2 LASTPIN (450 4600) $PN 41
J 0
(460 4610);
DISPLAY 0.617021 (460 4610);
PAINT ORANGE (460 4610);
FORCEPROP 2 LASTPIN (450 4550) $PN 29
J 0
(460 4560);
DISPLAY 0.617021 (460 4560);
PAINT ORANGE (460 4560);
FORCEPROP 2 LASTPIN (450 4500) $PN 30
J 0
(460 4510);
DISPLAY 0.617021 (460 4510);
PAINT ORANGE (460 4510);
FORCEPROP 2 LASTPIN (450 4450) $PN 18
J 0
(460 4460);
DISPLAY 0.617021 (460 4460);
PAINT ORANGE (460 4460);
FORCEPROP 2 LASTPIN (450 4400) $PN 19
J 0
(460 4410);
DISPLAY 0.617021 (460 4410);
PAINT ORANGE (460 4410);
FORCEPROP 2 LASTPIN (450 4350) $PN 7
J 0
(460 4360);
DISPLAY 0.617021 (460 4360);
PAINT ORANGE (460 4360);
FORCEPROP 2 LASTPIN (450 4300) $PN 8
J 0
(460 4310);
DISPLAY 0.617021 (460 4310);
PAINT ORANGE (460 4310);
FORCEPROP 2 LASTPIN (450 4250) $PN 197
J 0
(460 4260);
DISPLAY 0.617021 (460 4260);
PAINT ORANGE (460 4260);
FORCEPROP 2 LASTPIN (450 4200) $PN 196
J 0
(460 4210);
DISPLAY 0.617021 (460 4210);
PAINT ORANGE (460 4210);
FORCEPROP 2 LASTPIN (450 4150) $PN 278
J 0
(460 4160);
DISPLAY 0.617021 (460 4160);
PAINT ORANGE (460 4160);
FORCEPROP 2 LASTPIN (450 4100) $PN 277
J 0
(460 4110);
DISPLAY 0.617021 (460 4110);
PAINT ORANGE (460 4110);
FORCEPROP 2 LASTPIN (450 4050) $PN 267
J 0
(460 4060);
DISPLAY 0.617021 (460 4060);
PAINT ORANGE (460 4060);
FORCEPROP 2 LASTPIN (450 4000) $PN 266
J 0
(460 4010);
DISPLAY 0.617021 (460 4010);
PAINT ORANGE (460 4010);
FORCEPROP 2 LASTPIN (450 3950) $PN 256
J 0
(460 3960);
DISPLAY 0.617021 (460 3960);
PAINT ORANGE (460 3960);
FORCEPROP 2 LASTPIN (450 3900) $PN 255
J 0
(460 3910);
DISPLAY 0.617021 (460 3910);
PAINT ORANGE (460 3910);
FORCEPROP 2 LASTPIN (450 3850) $PN 245
J 0
(460 3860);
DISPLAY 0.617021 (460 3860);
PAINT ORANGE (460 3860);
FORCEPROP 2 LASTPIN (450 3800) $PN 244
J 0
(460 3810);
DISPLAY 0.617021 (460 3810);
PAINT ORANGE (460 3810);
FORCEPROP 2 LASTPIN (450 3750) $PN 186
J 0
(460 3760);
DISPLAY 0.617021 (460 3760);
PAINT ORANGE (460 3760);
FORCEPROP 2 LASTPIN (450 3700) $PN 185
J 0
(460 3710);
DISPLAY 0.617021 (460 3710);
PAINT ORANGE (460 3710);
FORCEPROP 2 LASTPIN (450 3650) $PN 175
J 0
(460 3660);
DISPLAY 0.617021 (460 3660);
PAINT ORANGE (460 3660);
FORCEPROP 2 LASTPIN (450 3600) $PN 174
J 0
(460 3610);
DISPLAY 0.617021 (460 3610);
PAINT ORANGE (460 3610);
FORCEPROP 2 LASTPIN (450 3550) $PN 164
J 0
(460 3560);
DISPLAY 0.617021 (460 3560);
PAINT ORANGE (460 3560);
FORCEPROP 2 LASTPIN (450 3500) $PN 163
J 0
(460 3510);
DISPLAY 0.617021 (460 3510);
PAINT ORANGE (460 3510);
FORCEPROP 2 LASTPIN (450 3450) $PN 153
J 0
(460 3460);
DISPLAY 0.617021 (460 3460);
PAINT ORANGE (460 3460);
FORCEPROP 2 LASTPIN (450 3400) $PN 152
J 0
(460 3410);
DISPLAY 0.617021 (460 3410);
PAINT ORANGE (460 3410);
FORCEPROP 2 LASTPIN (450 4900) $PN 122
J 0
(460 4910);
DISPLAY 0.617021 (460 4910);
PAINT ORANGE (460 4910);
FORCEPROP 1 LAST PACK_TYPE PIP
J 0
(-400 5450);
PAINT SKYBLUE (-400 5450);
DISPLAY INVISIBLE (-400 5450);
FORCEPROP 2 LAST BOM_COST MEM
J 0
(0 4300);
PAINT ORANGE (0 4300);
DISPLAY INVISIBLE (0 4300);
FORCEPROP 2 LAST CDS_LIB mstr_sconn
J 0
(0 4300);
PAINT ORANGE (0 4300);
DISPLAY INVISIBLE (0 4300);
FORCEPROP 2 LAST SEC_TYPE PIP
J 0
(-400 5450);
DISPLAY 1.021277 (-400 5450);
PAINT ORANGE (-400 5450);
DISPLAY INVISIBLE (-400 5450);
FORCEPROP 2 LAST SEC 2
J 0
(-400 5450);
DISPLAY 0.680851 (-400 5450);
PAINT MONO (-400 5450);
DISPLAY INVISIBLE (-400 5450);
FORCEPROP 2 LAST CDS_LOCATION J4G2
J 0
(-400 5400);
DISPLAY 0.617021 (-400 5400);
PAINT AQUA (-400 5400);
DISPLAY INVISIBLE (-400 5400);
FORCEPROP 1 LAST PATH I61
J 0
(0 5350);
PAINT GREEN (0 5350);
DISPLAY INVISIBLE (0 5350);
FORCEPROP 2 LAST ROOM DDR4_CH_B
J 0
(-400 5500);
PAINT ORANGE (-400 5500);
DISPLAY INVISIBLE (-400 5500);
FORCEADD TAP..6
R 2
(-1700 3750);
FORCEPROP 3 LASTPIN (-1750 3750) SIG_NAME M_B_DQ<47>
J 0
(-1740 3760);
DISPLAY 0.659574 (-1740 3760);
PAINT MONO (-1740 3760);
DISPLAY INVISIBLE (-1740 3760);
FORCEPROP 1 LASTPIN (-1750 3750) BN 47
J 2
(-1700 3760);
DISPLAY 0.617021 (-1700 3760);
PAINT PINK (-1700 3760);
FORCEPROP 2 LAST CDS_LIB mstr_standard
J 2
(-1700 3750);
DISPLAY 0.787234 (-1700 3750);
PAINT MONO (-1700 3750);
DISPLAY INVISIBLE (-1700 3750);
FORCEPROP 1 LAST BODY_TYPE PLUMBING
J 2
(-1700 3700);
DISPLAY 1.234043 (-1700 3700);
PAINT GREEN (-1700 3700);
DISPLAY INVISIBLE (-1700 3700);
FORCEPROP 1 LAST HDL_TAP TRUE
J 2
(-2025 3625);
DISPLAY 1.234043 (-2025 3625);
PAINT GREEN (-2025 3625);
DISPLAY INVISIBLE (-2025 3625);
FORCEPROP 1 LAST PATH I62
J 2
(-1700 3750);
DISPLAY 0.936170 (-1700 3750);
PAINT GREEN (-1700 3750);
DISPLAY INVISIBLE (-1700 3750);
FORCEADD TAP..6
R 2
(-1700 3800);
FORCEPROP 3 LASTPIN (-1750 3800) SIG_NAME M_B_DQ<46>
J 0
(-1740 3810);
DISPLAY 0.659574 (-1740 3810);
PAINT MONO (-1740 3810);
DISPLAY INVISIBLE (-1740 3810);
FORCEPROP 1 LASTPIN (-1750 3800) BN 46
J 2
(-1700 3810);
DISPLAY 0.617021 (-1700 3810);
PAINT PINK (-1700 3810);
FORCEPROP 2 LAST CDS_LIB mstr_standard
J 2
(-1700 3800);
DISPLAY 0.787234 (-1700 3800);
PAINT MONO (-1700 3800);
DISPLAY INVISIBLE (-1700 3800);
FORCEPROP 1 LAST BODY_TYPE PLUMBING
J 2
(-1700 3750);
DISPLAY 1.234043 (-1700 3750);
PAINT GREEN (-1700 3750);
DISPLAY INVISIBLE (-1700 3750);
FORCEPROP 1 LAST HDL_TAP TRUE
J 2
(-2025 3675);
DISPLAY 1.234043 (-2025 3675);
PAINT GREEN (-2025 3675);
DISPLAY INVISIBLE (-2025 3675);
FORCEPROP 1 LAST PATH I63
J 2
(-1700 3800);
DISPLAY 0.936170 (-1700 3800);
PAINT GREEN (-1700 3800);
DISPLAY INVISIBLE (-1700 3800);
FORCEADD TAP..6
R 2
(-1700 3850);
FORCEPROP 3 LASTPIN (-1750 3850) SIG_NAME M_B_DQ<49>
J 0
(-1740 3860);
DISPLAY 0.659574 (-1740 3860);
PAINT MONO (-1740 3860);
DISPLAY INVISIBLE (-1740 3860);
FORCEPROP 1 LASTPIN (-1750 3850) BN 49
J 2
(-1700 3860);
DISPLAY 0.617021 (-1700 3860);
PAINT PINK (-1700 3860);
FORCEPROP 2 LAST CDS_LIB mstr_standard
J 2
(-1700 3850);
DISPLAY 0.787234 (-1700 3850);
PAINT MONO (-1700 3850);
DISPLAY INVISIBLE (-1700 3850);
FORCEPROP 1 LAST BODY_TYPE PLUMBING
J 2
(-1700 3800);
DISPLAY 1.234043 (-1700 3800);
PAINT GREEN (-1700 3800);
DISPLAY INVISIBLE (-1700 3800);
FORCEPROP 1 LAST HDL_TAP TRUE
J 2
(-2025 3725);
DISPLAY 1.234043 (-2025 3725);
PAINT GREEN (-2025 3725);
DISPLAY INVISIBLE (-2025 3725);
FORCEPROP 1 LAST PATH I64
J 2
(-1700 3850);
DISPLAY 0.936170 (-1700 3850);
PAINT GREEN (-1700 3850);
DISPLAY INVISIBLE (-1700 3850);
FORCEADD TAP..6
R 2
(-1700 3700);
FORCEPROP 3 LASTPIN (-1750 3700) SIG_NAME M_B_DQ<44>
J 0
(-1740 3710);
DISPLAY 0.659574 (-1740 3710);
PAINT MONO (-1740 3710);
DISPLAY INVISIBLE (-1740 3710);
FORCEPROP 1 LASTPIN (-1750 3700) BN 44
J 2
(-1700 3710);
DISPLAY 0.617021 (-1700 3710);
PAINT PINK (-1700 3710);
FORCEPROP 2 LAST CDS_LIB mstr_standard
J 2
(-1700 3700);
DISPLAY 0.787234 (-1700 3700);
PAINT MONO (-1700 3700);
DISPLAY INVISIBLE (-1700 3700);
FORCEPROP 1 LAST BODY_TYPE PLUMBING
J 2
(-1700 3650);
DISPLAY 1.234043 (-1700 3650);
PAINT GREEN (-1700 3650);
DISPLAY INVISIBLE (-1700 3650);
FORCEPROP 1 LAST HDL_TAP TRUE
J 2
(-2025 3575);
DISPLAY 1.234043 (-2025 3575);
PAINT GREEN (-2025 3575);
DISPLAY INVISIBLE (-2025 3575);
FORCEPROP 1 LAST PATH I65
J 2
(-1700 3700);
DISPLAY 0.936170 (-1700 3700);
PAINT GREEN (-1700 3700);
DISPLAY INVISIBLE (-1700 3700);
FORCEADD TAP..6
R 2
(-1700 3650);
FORCEPROP 3 LASTPIN (-1750 3650) SIG_NAME M_B_DQ<45>
J 0
(-1740 3660);
DISPLAY 0.659574 (-1740 3660);
PAINT MONO (-1740 3660);
DISPLAY INVISIBLE (-1740 3660);
FORCEPROP 1 LASTPIN (-1750 3650) BN 45
J 2
(-1700 3660);
DISPLAY 0.617021 (-1700 3660);
PAINT PINK (-1700 3660);
FORCEPROP 2 LAST CDS_LIB mstr_standard
J 2
(-1700 3650);
DISPLAY 0.787234 (-1700 3650);
PAINT MONO (-1700 3650);
DISPLAY INVISIBLE (-1700 3650);
FORCEPROP 1 LAST BODY_TYPE PLUMBING
J 2
(-1700 3600);
DISPLAY 1.234043 (-1700 3600);
PAINT GREEN (-1700 3600);
DISPLAY INVISIBLE (-1700 3600);
FORCEPROP 1 LAST HDL_TAP TRUE
J 2
(-2025 3525);
DISPLAY 1.234043 (-2025 3525);
PAINT GREEN (-2025 3525);
DISPLAY INVISIBLE (-2025 3525);
FORCEPROP 1 LAST PATH I66
J 2
(-1700 3650);
DISPLAY 0.936170 (-1700 3650);
PAINT GREEN (-1700 3650);
DISPLAY INVISIBLE (-1700 3650);
FORCEADD TAP..6
R 2
(-1700 3600);
FORCEPROP 3 LASTPIN (-1750 3600) SIG_NAME M_B_DQ<42>
J 0
(-1740 3610);
DISPLAY 0.659574 (-1740 3610);
PAINT MONO (-1740 3610);
DISPLAY INVISIBLE (-1740 3610);
FORCEPROP 1 LASTPIN (-1750 3600) BN 42
J 2
(-1700 3610);
DISPLAY 0.617021 (-1700 3610);
PAINT PINK (-1700 3610);
FORCEPROP 2 LAST CDS_LIB mstr_standard
J 2
(-1700 3600);
DISPLAY 0.787234 (-1700 3600);
PAINT MONO (-1700 3600);
DISPLAY INVISIBLE (-1700 3600);
FORCEPROP 1 LAST BODY_TYPE PLUMBING
J 2
(-1700 3550);
DISPLAY 1.234043 (-1700 3550);
PAINT GREEN (-1700 3550);
DISPLAY INVISIBLE (-1700 3550);
FORCEPROP 1 LAST HDL_TAP TRUE
J 2
(-2025 3475);
DISPLAY 1.234043 (-2025 3475);
PAINT GREEN (-2025 3475);
DISPLAY INVISIBLE (-2025 3475);
FORCEPROP 1 LAST PATH I67
J 2
(-1700 3600);
DISPLAY 0.936170 (-1700 3600);
PAINT GREEN (-1700 3600);
DISPLAY INVISIBLE (-1700 3600);
FORCEADD TAP..6
R 2
(-1700 3550);
FORCEPROP 3 LASTPIN (-1750 3550) SIG_NAME M_B_DQ<43>
J 0
(-1740 3560);
DISPLAY 0.659574 (-1740 3560);
PAINT MONO (-1740 3560);
DISPLAY INVISIBLE (-1740 3560);
FORCEPROP 1 LASTPIN (-1750 3550) BN 43
J 2
(-1700 3560);
DISPLAY 0.617021 (-1700 3560);
PAINT PINK (-1700 3560);
FORCEPROP 2 LAST CDS_LIB mstr_standard
J 2
(-1700 3550);
DISPLAY 0.787234 (-1700 3550);
PAINT MONO (-1700 3550);
DISPLAY INVISIBLE (-1700 3550);
FORCEPROP 1 LAST BODY_TYPE PLUMBING
J 2
(-1700 3500);
DISPLAY 1.234043 (-1700 3500);
PAINT GREEN (-1700 3500);
DISPLAY INVISIBLE (-1700 3500);
FORCEPROP 1 LAST HDL_TAP TRUE
J 2
(-2025 3425);
DISPLAY 1.234043 (-2025 3425);
PAINT GREEN (-2025 3425);
DISPLAY INVISIBLE (-2025 3425);
FORCEPROP 1 LAST PATH I68
J 2
(-1700 3550);
DISPLAY 0.936170 (-1700 3550);
PAINT GREEN (-1700 3550);
DISPLAY INVISIBLE (-1700 3550);
FORCEADD TAP..6
R 2
(-1700 3500);
FORCEPROP 3 LASTPIN (-1750 3500) SIG_NAME M_B_DQ<40>
J 0
(-1740 3510);
DISPLAY 0.659574 (-1740 3510);
PAINT MONO (-1740 3510);
DISPLAY INVISIBLE (-1740 3510);
FORCEPROP 1 LASTPIN (-1750 3500) BN 40
J 2
(-1700 3510);
DISPLAY 0.617021 (-1700 3510);
PAINT PINK (-1700 3510);
FORCEPROP 2 LAST CDS_LIB mstr_standard
J 2
(-1700 3500);
DISPLAY 0.787234 (-1700 3500);
PAINT MONO (-1700 3500);
DISPLAY INVISIBLE (-1700 3500);
FORCEPROP 1 LAST BODY_TYPE PLUMBING
J 2
(-1700 3450);
DISPLAY 1.234043 (-1700 3450);
PAINT GREEN (-1700 3450);
DISPLAY INVISIBLE (-1700 3450);
FORCEPROP 1 LAST HDL_TAP TRUE
J 2
(-2025 3375);
DISPLAY 1.234043 (-2025 3375);
PAINT GREEN (-2025 3375);
DISPLAY INVISIBLE (-2025 3375);
FORCEPROP 1 LAST PATH I69
J 2
(-1700 3500);
DISPLAY 0.936170 (-1700 3500);
PAINT GREEN (-1700 3500);
DISPLAY INVISIBLE (-1700 3500);
FORCEADD TAP..6
R 2
(900 5000);
FORCEPROP 3 LASTPIN (850 5000) SIG_NAME M_B_DQS_DN<16>
J 0
(860 5010);
DISPLAY 0.659574 (860 5010);
PAINT MONO (860 5010);
DISPLAY INVISIBLE (860 5010);
FORCEPROP 1 LASTPIN (850 5000) BN 16
J 2
(900 5010);
DISPLAY 0.617021 (900 5010);
PAINT PINK (900 5010);
FORCEPROP 2 LAST CDS_LIB mstr_standard
J 0
(900 5000);
DISPLAY 0.787234 (900 5000);
PAINT MONO (900 5000);
DISPLAY INVISIBLE (900 5000);
FORCEPROP 1 LAST BODY_TYPE PLUMBING
J 2
(900 4950);
DISPLAY 1.234043 (900 4950);
PAINT GREEN (900 4950);
DISPLAY INVISIBLE (900 4950);
FORCEPROP 1 LAST HDL_TAP TRUE
J 2
(575 4875);
DISPLAY 1.234043 (575 4875);
PAINT GREEN (575 4875);
DISPLAY INVISIBLE (575 4875);
FORCEPROP 1 LAST PATH I7
J 2
(900 5000);
DISPLAY 0.936170 (900 5000);
PAINT GREEN (900 5000);
DISPLAY INVISIBLE (900 5000);
FORCEADD TAP..6
R 2
(-1700 3400);
FORCEPROP 3 LASTPIN (-1750 3400) SIG_NAME M_B_DQ<38>
J 0
(-1740 3410);
DISPLAY 0.659574 (-1740 3410);
PAINT MONO (-1740 3410);
DISPLAY INVISIBLE (-1740 3410);
FORCEPROP 1 LASTPIN (-1750 3400) BN 38
J 2
(-1700 3410);
DISPLAY 0.617021 (-1700 3410);
PAINT PINK (-1700 3410);
FORCEPROP 2 LAST CDS_LIB mstr_standard
J 2
(-1700 3400);
DISPLAY 0.787234 (-1700 3400);
PAINT MONO (-1700 3400);
DISPLAY INVISIBLE (-1700 3400);
FORCEPROP 1 LAST BODY_TYPE PLUMBING
J 2
(-1700 3350);
DISPLAY 1.234043 (-1700 3350);
PAINT GREEN (-1700 3350);
DISPLAY INVISIBLE (-1700 3350);
FORCEPROP 1 LAST HDL_TAP TRUE
J 2
(-2025 3275);
DISPLAY 1.234043 (-2025 3275);
PAINT GREEN (-2025 3275);
DISPLAY INVISIBLE (-2025 3275);
FORCEPROP 1 LAST PATH I70
J 2
(-1700 3400);
DISPLAY 0.936170 (-1700 3400);
PAINT GREEN (-1700 3400);
DISPLAY INVISIBLE (-1700 3400);
FORCEADD TAP..6
R 2
(-1700 3450);
FORCEPROP 3 LASTPIN (-1750 3450) SIG_NAME M_B_DQ<41>
J 0
(-1740 3460);
DISPLAY 0.659574 (-1740 3460);
PAINT MONO (-1740 3460);
DISPLAY INVISIBLE (-1740 3460);
FORCEPROP 1 LASTPIN (-1750 3450) BN 41
J 2
(-1700 3460);
DISPLAY 0.617021 (-1700 3460);
PAINT PINK (-1700 3460);
FORCEPROP 2 LAST CDS_LIB mstr_standard
J 2
(-1700 3450);
DISPLAY 0.787234 (-1700 3450);
PAINT MONO (-1700 3450);
DISPLAY INVISIBLE (-1700 3450);
FORCEPROP 1 LAST BODY_TYPE PLUMBING
J 2
(-1700 3400);
DISPLAY 1.234043 (-1700 3400);
PAINT GREEN (-1700 3400);
DISPLAY INVISIBLE (-1700 3400);
FORCEPROP 1 LAST HDL_TAP TRUE
J 2
(-2025 3325);
DISPLAY 1.234043 (-2025 3325);
PAINT GREEN (-2025 3325);
DISPLAY INVISIBLE (-2025 3325);
FORCEPROP 1 LAST PATH I71
J 2
(-1700 3450);
DISPLAY 0.936170 (-1700 3450);
PAINT GREEN (-1700 3450);
DISPLAY INVISIBLE (-1700 3450);
FORCEADD TAP..6
R 2
(-1700 3250);
FORCEPROP 3 LASTPIN (-1750 3250) SIG_NAME M_B_DQ<37>
J 0
(-1740 3260);
DISPLAY 0.659574 (-1740 3260);
PAINT MONO (-1740 3260);
DISPLAY INVISIBLE (-1740 3260);
FORCEPROP 1 LASTPIN (-1750 3250) BN 37
J 2
(-1700 3260);
DISPLAY 0.617021 (-1700 3260);
PAINT PINK (-1700 3260);
FORCEPROP 2 LAST CDS_LIB mstr_standard
J 2
(-1700 3250);
DISPLAY 0.787234 (-1700 3250);
PAINT MONO (-1700 3250);
DISPLAY INVISIBLE (-1700 3250);
FORCEPROP 1 LAST BODY_TYPE PLUMBING
J 2
(-1700 3200);
DISPLAY 1.234043 (-1700 3200);
PAINT GREEN (-1700 3200);
DISPLAY INVISIBLE (-1700 3200);
FORCEPROP 1 LAST HDL_TAP TRUE
J 2
(-2025 3125);
DISPLAY 1.234043 (-2025 3125);
PAINT GREEN (-2025 3125);
DISPLAY INVISIBLE (-2025 3125);
FORCEPROP 1 LAST PATH I72
J 2
(-1700 3250);
DISPLAY 0.936170 (-1700 3250);
PAINT GREEN (-1700 3250);
DISPLAY INVISIBLE (-1700 3250);
FORCEADD TAP..6
R 2
(-1700 3300);
FORCEPROP 3 LASTPIN (-1750 3300) SIG_NAME M_B_DQ<36>
J 0
(-1740 3310);
DISPLAY 0.659574 (-1740 3310);
PAINT MONO (-1740 3310);
DISPLAY INVISIBLE (-1740 3310);
FORCEPROP 1 LASTPIN (-1750 3300) BN 36
J 2
(-1700 3310);
DISPLAY 0.617021 (-1700 3310);
PAINT PINK (-1700 3310);
FORCEPROP 2 LAST CDS_LIB mstr_standard
J 2
(-1700 3300);
DISPLAY 0.787234 (-1700 3300);
PAINT MONO (-1700 3300);
DISPLAY INVISIBLE (-1700 3300);
FORCEPROP 1 LAST BODY_TYPE PLUMBING
J 2
(-1700 3250);
DISPLAY 1.234043 (-1700 3250);
PAINT GREEN (-1700 3250);
DISPLAY INVISIBLE (-1700 3250);
FORCEPROP 1 LAST HDL_TAP TRUE
J 2
(-2025 3175);
DISPLAY 1.234043 (-2025 3175);
PAINT GREEN (-2025 3175);
DISPLAY INVISIBLE (-2025 3175);
FORCEPROP 1 LAST PATH I73
J 2
(-1700 3300);
DISPLAY 0.936170 (-1700 3300);
PAINT GREEN (-1700 3300);
DISPLAY INVISIBLE (-1700 3300);
FORCEADD TAP..6
R 2
(-1700 3350);
FORCEPROP 3 LASTPIN (-1750 3350) SIG_NAME M_B_DQ<39>
J 0
(-1740 3360);
DISPLAY 0.659574 (-1740 3360);
PAINT MONO (-1740 3360);
DISPLAY INVISIBLE (-1740 3360);
FORCEPROP 1 LASTPIN (-1750 3350) BN 39
J 2
(-1700 3360);
DISPLAY 0.617021 (-1700 3360);
PAINT PINK (-1700 3360);
FORCEPROP 2 LAST CDS_LIB mstr_standard
J 2
(-1700 3350);
DISPLAY 0.787234 (-1700 3350);
PAINT MONO (-1700 3350);
DISPLAY INVISIBLE (-1700 3350);
FORCEPROP 1 LAST BODY_TYPE PLUMBING
J 2
(-1700 3300);
DISPLAY 1.234043 (-1700 3300);
PAINT GREEN (-1700 3300);
DISPLAY INVISIBLE (-1700 3300);
FORCEPROP 1 LAST HDL_TAP TRUE
J 2
(-2025 3225);
DISPLAY 1.234043 (-2025 3225);
PAINT GREEN (-2025 3225);
DISPLAY INVISIBLE (-2025 3225);
FORCEPROP 1 LAST PATH I74
J 2
(-1700 3350);
DISPLAY 0.936170 (-1700 3350);
PAINT GREEN (-1700 3350);
DISPLAY INVISIBLE (-1700 3350);
FORCEADD TAP..6
R 2
(-1700 3150);
FORCEPROP 3 LASTPIN (-1750 3150) SIG_NAME M_B_DQ<35>
J 0
(-1740 3160);
DISPLAY 0.659574 (-1740 3160);
PAINT MONO (-1740 3160);
DISPLAY INVISIBLE (-1740 3160);
FORCEPROP 1 LASTPIN (-1750 3150) BN 35
J 2
(-1700 3160);
DISPLAY 0.617021 (-1700 3160);
PAINT PINK (-1700 3160);
FORCEPROP 2 LAST CDS_LIB mstr_standard
J 2
(-1700 3150);
DISPLAY 0.787234 (-1700 3150);
PAINT MONO (-1700 3150);
DISPLAY INVISIBLE (-1700 3150);
FORCEPROP 1 LAST BODY_TYPE PLUMBING
J 2
(-1700 3100);
DISPLAY 1.234043 (-1700 3100);
PAINT GREEN (-1700 3100);
DISPLAY INVISIBLE (-1700 3100);
FORCEPROP 1 LAST HDL_TAP TRUE
J 2
(-2025 3025);
DISPLAY 1.234043 (-2025 3025);
PAINT GREEN (-2025 3025);
DISPLAY INVISIBLE (-2025 3025);
FORCEPROP 1 LAST PATH I75
J 2
(-1700 3150);
DISPLAY 0.936170 (-1700 3150);
PAINT GREEN (-1700 3150);
DISPLAY INVISIBLE (-1700 3150);
FORCEADD TAP..6
R 2
(-1700 3200);
FORCEPROP 3 LASTPIN (-1750 3200) SIG_NAME M_B_DQ<34>
J 0
(-1740 3210);
DISPLAY 0.659574 (-1740 3210);
PAINT MONO (-1740 3210);
DISPLAY INVISIBLE (-1740 3210);
FORCEPROP 1 LASTPIN (-1750 3200) BN 34
J 2
(-1700 3210);
DISPLAY 0.617021 (-1700 3210);
PAINT PINK (-1700 3210);
FORCEPROP 2 LAST CDS_LIB mstr_standard
J 2
(-1700 3200);
DISPLAY 0.787234 (-1700 3200);
PAINT MONO (-1700 3200);
DISPLAY INVISIBLE (-1700 3200);
FORCEPROP 1 LAST BODY_TYPE PLUMBING
J 2
(-1700 3150);
DISPLAY 1.234043 (-1700 3150);
PAINT GREEN (-1700 3150);
DISPLAY INVISIBLE (-1700 3150);
FORCEPROP 1 LAST HDL_TAP TRUE
J 2
(-2025 3075);
DISPLAY 1.234043 (-2025 3075);
PAINT GREEN (-2025 3075);
DISPLAY INVISIBLE (-2025 3075);
FORCEPROP 1 LAST PATH I76
J 2
(-1700 3200);
DISPLAY 0.936170 (-1700 3200);
PAINT GREEN (-1700 3200);
DISPLAY INVISIBLE (-1700 3200);
FORCEADD TAP..6
R 2
(-1700 3100);
FORCEPROP 3 LASTPIN (-1750 3100) SIG_NAME M_B_DQ<32>
J 0
(-1740 3110);
DISPLAY 0.659574 (-1740 3110);
PAINT MONO (-1740 3110);
DISPLAY INVISIBLE (-1740 3110);
FORCEPROP 1 LASTPIN (-1750 3100) BN 32
J 2
(-1700 3110);
DISPLAY 0.617021 (-1700 3110);
PAINT PINK (-1700 3110);
FORCEPROP 2 LAST CDS_LIB mstr_standard
J 2
(-1700 3100);
DISPLAY 0.787234 (-1700 3100);
PAINT MONO (-1700 3100);
DISPLAY INVISIBLE (-1700 3100);
FORCEPROP 1 LAST BODY_TYPE PLUMBING
J 2
(-1700 3050);
DISPLAY 1.234043 (-1700 3050);
PAINT GREEN (-1700 3050);
DISPLAY INVISIBLE (-1700 3050);
FORCEPROP 1 LAST HDL_TAP TRUE
J 2
(-2025 2975);
DISPLAY 1.234043 (-2025 2975);
PAINT GREEN (-2025 2975);
DISPLAY INVISIBLE (-2025 2975);
FORCEPROP 1 LAST PATH I77
J 2
(-1700 3100);
DISPLAY 0.936170 (-1700 3100);
PAINT GREEN (-1700 3100);
DISPLAY INVISIBLE (-1700 3100);
FORCEADD TAP..6
R 2
(-1700 3050);
FORCEPROP 3 LASTPIN (-1750 3050) SIG_NAME M_B_DQ<33>
J 0
(-1740 3060);
DISPLAY 0.659574 (-1740 3060);
PAINT MONO (-1740 3060);
DISPLAY INVISIBLE (-1740 3060);
FORCEPROP 1 LASTPIN (-1750 3050) BN 33
J 2
(-1700 3060);
DISPLAY 0.617021 (-1700 3060);
PAINT PINK (-1700 3060);
FORCEPROP 2 LAST CDS_LIB mstr_standard
J 2
(-1700 3050);
DISPLAY 0.787234 (-1700 3050);
PAINT MONO (-1700 3050);
DISPLAY INVISIBLE (-1700 3050);
FORCEPROP 1 LAST BODY_TYPE PLUMBING
J 2
(-1700 3000);
DISPLAY 1.234043 (-1700 3000);
PAINT GREEN (-1700 3000);
DISPLAY INVISIBLE (-1700 3000);
FORCEPROP 1 LAST HDL_TAP TRUE
J 2
(-2025 2925);
DISPLAY 1.234043 (-2025 2925);
PAINT GREEN (-2025 2925);
DISPLAY INVISIBLE (-2025 2925);
FORCEPROP 1 LAST PATH I78
J 2
(-1700 3050);
DISPLAY 0.936170 (-1700 3050);
PAINT GREEN (-1700 3050);
DISPLAY INVISIBLE (-1700 3050);
FORCEADD TAP..6
R 2
(-1700 3000);
FORCEPROP 3 LASTPIN (-1750 3000) SIG_NAME M_B_DQ<30>
J 0
(-1740 3010);
DISPLAY 0.659574 (-1740 3010);
PAINT MONO (-1740 3010);
DISPLAY INVISIBLE (-1740 3010);
FORCEPROP 1 LASTPIN (-1750 3000) BN 30
J 2
(-1700 3010);
DISPLAY 0.617021 (-1700 3010);
PAINT PINK (-1700 3010);
FORCEPROP 2 LAST CDS_LIB mstr_standard
J 2
(-1700 3000);
DISPLAY 0.787234 (-1700 3000);
PAINT MONO (-1700 3000);
DISPLAY INVISIBLE (-1700 3000);
FORCEPROP 1 LAST BODY_TYPE PLUMBING
J 2
(-1700 2950);
DISPLAY 1.234043 (-1700 2950);
PAINT GREEN (-1700 2950);
DISPLAY INVISIBLE (-1700 2950);
FORCEPROP 1 LAST HDL_TAP TRUE
J 2
(-2025 2875);
DISPLAY 1.234043 (-2025 2875);
PAINT GREEN (-2025 2875);
DISPLAY INVISIBLE (-2025 2875);
FORCEPROP 1 LAST PATH I79
J 2
(-1700 3000);
DISPLAY 0.936170 (-1700 3000);
PAINT GREEN (-1700 3000);
DISPLAY INVISIBLE (-1700 3000);
FORCEADD TAP..6
R 2
(900 4800);
FORCEPROP 3 LASTPIN (850 4800) SIG_NAME M_B_DQS_DN<14>
J 0
(860 4810);
DISPLAY 0.659574 (860 4810);
PAINT MONO (860 4810);
DISPLAY INVISIBLE (860 4810);
FORCEPROP 1 LASTPIN (850 4800) BN 14
J 2
(900 4810);
DISPLAY 0.617021 (900 4810);
PAINT PINK (900 4810);
FORCEPROP 2 LAST CDS_LIB mstr_standard
J 0
(900 4800);
DISPLAY 0.787234 (900 4800);
PAINT MONO (900 4800);
DISPLAY INVISIBLE (900 4800);
FORCEPROP 1 LAST BODY_TYPE PLUMBING
J 2
(900 4750);
DISPLAY 1.234043 (900 4750);
PAINT GREEN (900 4750);
DISPLAY INVISIBLE (900 4750);
FORCEPROP 1 LAST HDL_TAP TRUE
J 2
(575 4675);
DISPLAY 1.234043 (575 4675);
PAINT GREEN (575 4675);
DISPLAY INVISIBLE (575 4675);
FORCEPROP 1 LAST PATH I8
J 2
(900 4800);
DISPLAY 0.936170 (900 4800);
PAINT GREEN (900 4800);
DISPLAY INVISIBLE (900 4800);
FORCEADD TAP..6
R 2
(-1700 2850);
FORCEPROP 3 LASTPIN (-1750 2850) SIG_NAME M_B_DQ<29>
J 0
(-1740 2860);
DISPLAY 0.659574 (-1740 2860);
PAINT MONO (-1740 2860);
DISPLAY INVISIBLE (-1740 2860);
FORCEPROP 1 LASTPIN (-1750 2850) BN 29
J 2
(-1700 2860);
DISPLAY 0.617021 (-1700 2860);
PAINT PINK (-1700 2860);
FORCEPROP 2 LAST CDS_LIB mstr_standard
J 2
(-1700 2850);
DISPLAY 0.787234 (-1700 2850);
PAINT MONO (-1700 2850);
DISPLAY INVISIBLE (-1700 2850);
FORCEPROP 1 LAST BODY_TYPE PLUMBING
J 2
(-1700 2800);
DISPLAY 1.234043 (-1700 2800);
PAINT GREEN (-1700 2800);
DISPLAY INVISIBLE (-1700 2800);
FORCEPROP 1 LAST HDL_TAP TRUE
J 2
(-2025 2725);
DISPLAY 1.234043 (-2025 2725);
PAINT GREEN (-2025 2725);
DISPLAY INVISIBLE (-2025 2725);
FORCEPROP 1 LAST PATH I80
J 2
(-1700 2850);
DISPLAY 0.936170 (-1700 2850);
PAINT GREEN (-1700 2850);
DISPLAY INVISIBLE (-1700 2850);
FORCEADD TAP..6
R 2
(-1700 2900);
FORCEPROP 3 LASTPIN (-1750 2900) SIG_NAME M_B_DQ<28>
J 0
(-1740 2910);
DISPLAY 0.659574 (-1740 2910);
PAINT MONO (-1740 2910);
DISPLAY INVISIBLE (-1740 2910);
FORCEPROP 1 LASTPIN (-1750 2900) BN 28
J 2
(-1700 2910);
DISPLAY 0.617021 (-1700 2910);
PAINT PINK (-1700 2910);
FORCEPROP 2 LAST CDS_LIB mstr_standard
J 2
(-1700 2900);
DISPLAY 0.787234 (-1700 2900);
PAINT MONO (-1700 2900);
DISPLAY INVISIBLE (-1700 2900);
FORCEPROP 1 LAST BODY_TYPE PLUMBING
J 2
(-1700 2850);
DISPLAY 1.234043 (-1700 2850);
PAINT GREEN (-1700 2850);
DISPLAY INVISIBLE (-1700 2850);
FORCEPROP 1 LAST HDL_TAP TRUE
J 2
(-2025 2775);
DISPLAY 1.234043 (-2025 2775);
PAINT GREEN (-2025 2775);
DISPLAY INVISIBLE (-2025 2775);
FORCEPROP 1 LAST PATH I81
J 2
(-1700 2900);
DISPLAY 0.936170 (-1700 2900);
PAINT GREEN (-1700 2900);
DISPLAY INVISIBLE (-1700 2900);
FORCEADD TAP..6
R 2
(-1700 2950);
FORCEPROP 3 LASTPIN (-1750 2950) SIG_NAME M_B_DQ<31>
J 0
(-1740 2960);
DISPLAY 0.659574 (-1740 2960);
PAINT MONO (-1740 2960);
DISPLAY INVISIBLE (-1740 2960);
FORCEPROP 1 LASTPIN (-1750 2950) BN 31
J 2
(-1700 2960);
DISPLAY 0.617021 (-1700 2960);
PAINT PINK (-1700 2960);
FORCEPROP 2 LAST CDS_LIB mstr_standard
J 2
(-1700 2950);
DISPLAY 0.787234 (-1700 2950);
PAINT MONO (-1700 2950);
DISPLAY INVISIBLE (-1700 2950);
FORCEPROP 1 LAST BODY_TYPE PLUMBING
J 2
(-1700 2900);
DISPLAY 1.234043 (-1700 2900);
PAINT GREEN (-1700 2900);
DISPLAY INVISIBLE (-1700 2900);
FORCEPROP 1 LAST HDL_TAP TRUE
J 2
(-2025 2825);
DISPLAY 1.234043 (-2025 2825);
PAINT GREEN (-2025 2825);
DISPLAY INVISIBLE (-2025 2825);
FORCEPROP 1 LAST PATH I82
J 2
(-1700 2950);
DISPLAY 0.936170 (-1700 2950);
PAINT GREEN (-1700 2950);
DISPLAY INVISIBLE (-1700 2950);
FORCEADD TAP..6
R 2
(-1700 2800);
FORCEPROP 3 LASTPIN (-1750 2800) SIG_NAME M_B_DQ<26>
J 0
(-1740 2810);
DISPLAY 0.659574 (-1740 2810);
PAINT MONO (-1740 2810);
DISPLAY INVISIBLE (-1740 2810);
FORCEPROP 1 LASTPIN (-1750 2800) BN 26
J 2
(-1700 2810);
DISPLAY 0.617021 (-1700 2810);
PAINT PINK (-1700 2810);
FORCEPROP 2 LAST CDS_LIB mstr_standard
J 2
(-1700 2800);
DISPLAY 0.787234 (-1700 2800);
PAINT MONO (-1700 2800);
DISPLAY INVISIBLE (-1700 2800);
FORCEPROP 1 LAST BODY_TYPE PLUMBING
J 2
(-1700 2750);
DISPLAY 1.234043 (-1700 2750);
PAINT GREEN (-1700 2750);
DISPLAY INVISIBLE (-1700 2750);
FORCEPROP 1 LAST HDL_TAP TRUE
J 2
(-2025 2675);
DISPLAY 1.234043 (-2025 2675);
PAINT GREEN (-2025 2675);
DISPLAY INVISIBLE (-2025 2675);
FORCEPROP 1 LAST PATH I83
J 2
(-1700 2800);
DISPLAY 0.936170 (-1700 2800);
PAINT GREEN (-1700 2800);
DISPLAY INVISIBLE (-1700 2800);
FORCEADD TAP..6
R 2
(-1700 2750);
FORCEPROP 3 LASTPIN (-1750 2750) SIG_NAME M_B_DQ<27>
J 0
(-1740 2760);
DISPLAY 0.659574 (-1740 2760);
PAINT MONO (-1740 2760);
DISPLAY INVISIBLE (-1740 2760);
FORCEPROP 1 LASTPIN (-1750 2750) BN 27
J 2
(-1700 2760);
DISPLAY 0.617021 (-1700 2760);
PAINT PINK (-1700 2760);
FORCEPROP 2 LAST CDS_LIB mstr_standard
J 2
(-1700 2750);
DISPLAY 0.787234 (-1700 2750);
PAINT MONO (-1700 2750);
DISPLAY INVISIBLE (-1700 2750);
FORCEPROP 1 LAST BODY_TYPE PLUMBING
J 2
(-1700 2700);
DISPLAY 1.234043 (-1700 2700);
PAINT GREEN (-1700 2700);
DISPLAY INVISIBLE (-1700 2700);
FORCEPROP 1 LAST HDL_TAP TRUE
J 2
(-2025 2625);
DISPLAY 1.234043 (-2025 2625);
PAINT GREEN (-2025 2625);
DISPLAY INVISIBLE (-2025 2625);
FORCEPROP 1 LAST PATH I84
J 2
(-1700 2750);
DISPLAY 0.936170 (-1700 2750);
PAINT GREEN (-1700 2750);
DISPLAY INVISIBLE (-1700 2750);
FORCEADD TAP..6
R 2
(-1700 2600);
FORCEPROP 3 LASTPIN (-1750 2600) SIG_NAME M_B_DQ<22>
J 0
(-1740 2610);
DISPLAY 0.659574 (-1740 2610);
PAINT MONO (-1740 2610);
DISPLAY INVISIBLE (-1740 2610);
FORCEPROP 1 LASTPIN (-1750 2600) BN 22
J 2
(-1700 2610);
DISPLAY 0.617021 (-1700 2610);
PAINT PINK (-1700 2610);
FORCEPROP 2 LAST CDS_LIB mstr_standard
J 2
(-1700 2600);
DISPLAY 0.787234 (-1700 2600);
PAINT MONO (-1700 2600);
DISPLAY INVISIBLE (-1700 2600);
FORCEPROP 1 LAST BODY_TYPE PLUMBING
J 2
(-1700 2550);
DISPLAY 1.234043 (-1700 2550);
PAINT GREEN (-1700 2550);
DISPLAY INVISIBLE (-1700 2550);
FORCEPROP 1 LAST HDL_TAP TRUE
J 2
(-2025 2475);
DISPLAY 1.234043 (-2025 2475);
PAINT GREEN (-2025 2475);
DISPLAY INVISIBLE (-2025 2475);
FORCEPROP 1 LAST PATH I85
J 2
(-1700 2600);
DISPLAY 0.936170 (-1700 2600);
PAINT GREEN (-1700 2600);
DISPLAY INVISIBLE (-1700 2600);
FORCEADD TAP..6
R 2
(-1700 2700);
FORCEPROP 3 LASTPIN (-1750 2700) SIG_NAME M_B_DQ<24>
J 0
(-1740 2710);
DISPLAY 0.659574 (-1740 2710);
PAINT MONO (-1740 2710);
DISPLAY INVISIBLE (-1740 2710);
FORCEPROP 1 LASTPIN (-1750 2700) BN 24
J 2
(-1700 2710);
DISPLAY 0.617021 (-1700 2710);
PAINT PINK (-1700 2710);
FORCEPROP 2 LAST CDS_LIB mstr_standard
J 2
(-1700 2700);
DISPLAY 0.787234 (-1700 2700);
PAINT MONO (-1700 2700);
DISPLAY INVISIBLE (-1700 2700);
FORCEPROP 1 LAST BODY_TYPE PLUMBING
J 2
(-1700 2650);
DISPLAY 1.234043 (-1700 2650);
PAINT GREEN (-1700 2650);
DISPLAY INVISIBLE (-1700 2650);
FORCEPROP 1 LAST HDL_TAP TRUE
J 2
(-2025 2575);
DISPLAY 1.234043 (-2025 2575);
PAINT GREEN (-2025 2575);
DISPLAY INVISIBLE (-2025 2575);
FORCEPROP 1 LAST PATH I86
J 2
(-1700 2700);
DISPLAY 0.936170 (-1700 2700);
PAINT GREEN (-1700 2700);
DISPLAY INVISIBLE (-1700 2700);
FORCEADD TAP..6
R 2
(-1700 2650);
FORCEPROP 3 LASTPIN (-1750 2650) SIG_NAME M_B_DQ<25>
J 0
(-1740 2660);
DISPLAY 0.659574 (-1740 2660);
PAINT MONO (-1740 2660);
DISPLAY INVISIBLE (-1740 2660);
FORCEPROP 1 LASTPIN (-1750 2650) BN 25
J 2
(-1700 2660);
DISPLAY 0.617021 (-1700 2660);
PAINT PINK (-1700 2660);
FORCEPROP 2 LAST CDS_LIB mstr_standard
J 2
(-1700 2650);
DISPLAY 0.787234 (-1700 2650);
PAINT MONO (-1700 2650);
DISPLAY INVISIBLE (-1700 2650);
FORCEPROP 1 LAST BODY_TYPE PLUMBING
J 2
(-1700 2600);
DISPLAY 1.234043 (-1700 2600);
PAINT GREEN (-1700 2600);
DISPLAY INVISIBLE (-1700 2600);
FORCEPROP 1 LAST HDL_TAP TRUE
J 2
(-2025 2525);
DISPLAY 1.234043 (-2025 2525);
PAINT GREEN (-2025 2525);
DISPLAY INVISIBLE (-2025 2525);
FORCEPROP 1 LAST PATH I87
J 2
(-1700 2650);
DISPLAY 0.936170 (-1700 2650);
PAINT GREEN (-1700 2650);
DISPLAY INVISIBLE (-1700 2650);
FORCEADD TAP..6
R 2
(-1700 2500);
FORCEPROP 3 LASTPIN (-1750 2500) SIG_NAME M_B_DQ<20>
J 0
(-1740 2510);
DISPLAY 0.659574 (-1740 2510);
PAINT MONO (-1740 2510);
DISPLAY INVISIBLE (-1740 2510);
FORCEPROP 1 LASTPIN (-1750 2500) BN 20
J 2
(-1700 2510);
DISPLAY 0.617021 (-1700 2510);
PAINT PINK (-1700 2510);
FORCEPROP 2 LAST CDS_LIB mstr_standard
J 2
(-1700 2500);
DISPLAY 0.787234 (-1700 2500);
PAINT MONO (-1700 2500);
DISPLAY INVISIBLE (-1700 2500);
FORCEPROP 1 LAST BODY_TYPE PLUMBING
J 2
(-1700 2450);
DISPLAY 1.234043 (-1700 2450);
PAINT GREEN (-1700 2450);
DISPLAY INVISIBLE (-1700 2450);
FORCEPROP 1 LAST HDL_TAP TRUE
J 2
(-2025 2375);
DISPLAY 1.234043 (-2025 2375);
PAINT GREEN (-2025 2375);
DISPLAY INVISIBLE (-2025 2375);
FORCEPROP 1 LAST PATH I88
J 2
(-1700 2500);
DISPLAY 0.936170 (-1700 2500);
PAINT GREEN (-1700 2500);
DISPLAY INVISIBLE (-1700 2500);
FORCEADD TAP..6
R 2
(-1700 2550);
FORCEPROP 3 LASTPIN (-1750 2550) SIG_NAME M_B_DQ<23>
J 0
(-1740 2560);
DISPLAY 0.659574 (-1740 2560);
PAINT MONO (-1740 2560);
DISPLAY INVISIBLE (-1740 2560);
FORCEPROP 1 LASTPIN (-1750 2550) BN 23
J 2
(-1700 2560);
DISPLAY 0.617021 (-1700 2560);
PAINT PINK (-1700 2560);
FORCEPROP 2 LAST CDS_LIB mstr_standard
J 2
(-1700 2550);
DISPLAY 0.787234 (-1700 2550);
PAINT MONO (-1700 2550);
DISPLAY INVISIBLE (-1700 2550);
FORCEPROP 1 LAST BODY_TYPE PLUMBING
J 2
(-1700 2500);
DISPLAY 1.234043 (-1700 2500);
PAINT GREEN (-1700 2500);
DISPLAY INVISIBLE (-1700 2500);
FORCEPROP 1 LAST HDL_TAP TRUE
J 2
(-2025 2425);
DISPLAY 1.234043 (-2025 2425);
PAINT GREEN (-2025 2425);
DISPLAY INVISIBLE (-2025 2425);
FORCEPROP 1 LAST PATH I89
J 2
(-1700 2550);
DISPLAY 0.936170 (-1700 2550);
PAINT GREEN (-1700 2550);
DISPLAY INVISIBLE (-1700 2550);
FORCEADD TAP..6
R 2
(700 4950);
FORCEPROP 3 LASTPIN (650 4950) SIG_NAME M_B_DQS_DP<15>
J 0
(660 4960);
DISPLAY 0.659574 (660 4960);
PAINT MONO (660 4960);
DISPLAY INVISIBLE (660 4960);
FORCEPROP 1 LASTPIN (650 4950) BN 15
J 2
(700 4960);
DISPLAY 0.617021 (700 4960);
PAINT PINK (700 4960);
FORCEPROP 2 LAST CDS_LIB mstr_standard
J 0
(700 4950);
DISPLAY 0.787234 (700 4950);
PAINT MONO (700 4950);
DISPLAY INVISIBLE (700 4950);
FORCEPROP 1 LAST BODY_TYPE PLUMBING
J 2
(700 4900);
DISPLAY 1.234043 (700 4900);
PAINT GREEN (700 4900);
DISPLAY INVISIBLE (700 4900);
FORCEPROP 1 LAST HDL_TAP TRUE
J 2
(375 4825);
DISPLAY 1.234043 (375 4825);
PAINT GREEN (375 4825);
DISPLAY INVISIBLE (375 4825);
FORCEPROP 1 LAST PATH I9
J 2
(700 4950);
DISPLAY 0.936170 (700 4950);
PAINT GREEN (700 4950);
DISPLAY INVISIBLE (700 4950);
FORCEADD TAP..6
R 2
(-1700 2450);
FORCEPROP 3 LASTPIN (-1750 2450) SIG_NAME M_B_DQ<21>
J 0
(-1740 2460);
DISPLAY 0.659574 (-1740 2460);
PAINT MONO (-1740 2460);
DISPLAY INVISIBLE (-1740 2460);
FORCEPROP 1 LASTPIN (-1750 2450) BN 21
J 2
(-1700 2460);
DISPLAY 0.617021 (-1700 2460);
PAINT PINK (-1700 2460);
FORCEPROP 2 LAST CDS_LIB mstr_standard
J 2
(-1700 2450);
DISPLAY 0.787234 (-1700 2450);
PAINT MONO (-1700 2450);
DISPLAY INVISIBLE (-1700 2450);
FORCEPROP 1 LAST BODY_TYPE PLUMBING
J 2
(-1700 2400);
DISPLAY 1.234043 (-1700 2400);
PAINT GREEN (-1700 2400);
DISPLAY INVISIBLE (-1700 2400);
FORCEPROP 1 LAST HDL_TAP TRUE
J 2
(-2025 2325);
DISPLAY 1.234043 (-2025 2325);
PAINT GREEN (-2025 2325);
DISPLAY INVISIBLE (-2025 2325);
FORCEPROP 1 LAST PATH I90
J 2
(-1700 2450);
DISPLAY 0.936170 (-1700 2450);
PAINT GREEN (-1700 2450);
DISPLAY INVISIBLE (-1700 2450);
FORCEADD TAP..6
R 2
(-1700 2400);
FORCEPROP 3 LASTPIN (-1750 2400) SIG_NAME M_B_DQ<18>
J 0
(-1740 2410);
DISPLAY 0.659574 (-1740 2410);
PAINT MONO (-1740 2410);
DISPLAY INVISIBLE (-1740 2410);
FORCEPROP 1 LASTPIN (-1750 2400) BN 18
J 2
(-1700 2410);
DISPLAY 0.617021 (-1700 2410);
PAINT PINK (-1700 2410);
FORCEPROP 2 LAST CDS_LIB mstr_standard
J 2
(-1700 2400);
DISPLAY 0.787234 (-1700 2400);
PAINT MONO (-1700 2400);
DISPLAY INVISIBLE (-1700 2400);
FORCEPROP 1 LAST BODY_TYPE PLUMBING
J 2
(-1700 2350);
DISPLAY 1.234043 (-1700 2350);
PAINT GREEN (-1700 2350);
DISPLAY INVISIBLE (-1700 2350);
FORCEPROP 1 LAST HDL_TAP TRUE
J 2
(-2025 2275);
DISPLAY 1.234043 (-2025 2275);
PAINT GREEN (-2025 2275);
DISPLAY INVISIBLE (-2025 2275);
FORCEPROP 1 LAST PATH I91
J 2
(-1700 2400);
DISPLAY 0.936170 (-1700 2400);
PAINT GREEN (-1700 2400);
DISPLAY INVISIBLE (-1700 2400);
FORCEADD TAP..6
R 2
(-1700 2350);
FORCEPROP 3 LASTPIN (-1750 2350) SIG_NAME M_B_DQ<19>
J 0
(-1740 2360);
DISPLAY 0.659574 (-1740 2360);
PAINT MONO (-1740 2360);
DISPLAY INVISIBLE (-1740 2360);
FORCEPROP 1 LASTPIN (-1750 2350) BN 19
J 2
(-1700 2360);
DISPLAY 0.617021 (-1700 2360);
PAINT PINK (-1700 2360);
FORCEPROP 2 LAST CDS_LIB mstr_standard
J 2
(-1700 2350);
DISPLAY 0.787234 (-1700 2350);
PAINT MONO (-1700 2350);
DISPLAY INVISIBLE (-1700 2350);
FORCEPROP 1 LAST BODY_TYPE PLUMBING
J 2
(-1700 2300);
DISPLAY 1.234043 (-1700 2300);
PAINT GREEN (-1700 2300);
DISPLAY INVISIBLE (-1700 2300);
FORCEPROP 1 LAST HDL_TAP TRUE
J 2
(-2025 2225);
DISPLAY 1.234043 (-2025 2225);
PAINT GREEN (-2025 2225);
DISPLAY INVISIBLE (-2025 2225);
FORCEPROP 1 LAST PATH I92
J 2
(-1700 2350);
DISPLAY 0.936170 (-1700 2350);
PAINT GREEN (-1700 2350);
DISPLAY INVISIBLE (-1700 2350);
FORCEADD TAP..6
R 2
(-1700 2250);
FORCEPROP 3 LASTPIN (-1750 2250) SIG_NAME M_B_DQ<17>
J 0
(-1740 2260);
DISPLAY 0.659574 (-1740 2260);
PAINT MONO (-1740 2260);
DISPLAY INVISIBLE (-1740 2260);
FORCEPROP 1 LASTPIN (-1750 2250) BN 17
J 2
(-1700 2260);
DISPLAY 0.617021 (-1700 2260);
PAINT PINK (-1700 2260);
FORCEPROP 2 LAST CDS_LIB mstr_standard
J 2
(-1700 2250);
DISPLAY 0.787234 (-1700 2250);
PAINT MONO (-1700 2250);
DISPLAY INVISIBLE (-1700 2250);
FORCEPROP 1 LAST BODY_TYPE PLUMBING
J 2
(-1700 2200);
DISPLAY 1.234043 (-1700 2200);
PAINT GREEN (-1700 2200);
DISPLAY INVISIBLE (-1700 2200);
FORCEPROP 1 LAST HDL_TAP TRUE
J 2
(-2025 2125);
DISPLAY 1.234043 (-2025 2125);
PAINT GREEN (-2025 2125);
DISPLAY INVISIBLE (-2025 2125);
FORCEPROP 1 LAST PATH I93
J 2
(-1700 2250);
DISPLAY 0.936170 (-1700 2250);
PAINT GREEN (-1700 2250);
DISPLAY INVISIBLE (-1700 2250);
FORCEADD TAP..6
R 2
(-1700 2300);
FORCEPROP 3 LASTPIN (-1750 2300) SIG_NAME M_B_DQ<16>
J 0
(-1740 2310);
DISPLAY 0.659574 (-1740 2310);
PAINT MONO (-1740 2310);
DISPLAY INVISIBLE (-1740 2310);
FORCEPROP 1 LASTPIN (-1750 2300) BN 16
J 2
(-1700 2310);
DISPLAY 0.617021 (-1700 2310);
PAINT PINK (-1700 2310);
FORCEPROP 2 LAST CDS_LIB mstr_standard
J 2
(-1700 2300);
DISPLAY 0.787234 (-1700 2300);
PAINT MONO (-1700 2300);
DISPLAY INVISIBLE (-1700 2300);
FORCEPROP 1 LAST BODY_TYPE PLUMBING
J 2
(-1700 2250);
DISPLAY 1.234043 (-1700 2250);
PAINT GREEN (-1700 2250);
DISPLAY INVISIBLE (-1700 2250);
FORCEPROP 1 LAST HDL_TAP TRUE
J 2
(-2025 2175);
DISPLAY 1.234043 (-2025 2175);
PAINT GREEN (-2025 2175);
DISPLAY INVISIBLE (-2025 2175);
FORCEPROP 1 LAST PATH I94
J 2
(-1700 2300);
DISPLAY 0.936170 (-1700 2300);
PAINT GREEN (-1700 2300);
DISPLAY INVISIBLE (-1700 2300);
FORCEADD TAP..6
R 2
(-1700 2100);
FORCEPROP 3 LASTPIN (-1750 2100) SIG_NAME M_B_DQ<12>
J 0
(-1740 2110);
DISPLAY 0.659574 (-1740 2110);
PAINT MONO (-1740 2110);
DISPLAY INVISIBLE (-1740 2110);
FORCEPROP 1 LASTPIN (-1750 2100) BN 12
J 2
(-1700 2110);
DISPLAY 0.617021 (-1700 2110);
PAINT PINK (-1700 2110);
FORCEPROP 2 LAST CDS_LIB mstr_standard
J 2
(-1700 2100);
DISPLAY 0.787234 (-1700 2100);
PAINT MONO (-1700 2100);
DISPLAY INVISIBLE (-1700 2100);
FORCEPROP 1 LAST BODY_TYPE PLUMBING
J 2
(-1700 2050);
DISPLAY 1.234043 (-1700 2050);
PAINT GREEN (-1700 2050);
DISPLAY INVISIBLE (-1700 2050);
FORCEPROP 1 LAST HDL_TAP TRUE
J 2
(-2025 1975);
DISPLAY 1.234043 (-2025 1975);
PAINT GREEN (-2025 1975);
DISPLAY INVISIBLE (-2025 1975);
FORCEPROP 1 LAST PATH I95
J 2
(-1700 2100);
DISPLAY 0.936170 (-1700 2100);
PAINT GREEN (-1700 2100);
DISPLAY INVISIBLE (-1700 2100);
FORCEADD TAP..6
R 2
(-1700 2150);
FORCEPROP 3 LASTPIN (-1750 2150) SIG_NAME M_B_DQ<15>
J 0
(-1740 2160);
DISPLAY 0.659574 (-1740 2160);
PAINT MONO (-1740 2160);
DISPLAY INVISIBLE (-1740 2160);
FORCEPROP 1 LASTPIN (-1750 2150) BN 15
J 2
(-1700 2160);
DISPLAY 0.617021 (-1700 2160);
PAINT PINK (-1700 2160);
FORCEPROP 2 LAST CDS_LIB mstr_standard
J 2
(-1700 2150);
DISPLAY 0.787234 (-1700 2150);
PAINT MONO (-1700 2150);
DISPLAY INVISIBLE (-1700 2150);
FORCEPROP 1 LAST BODY_TYPE PLUMBING
J 2
(-1700 2100);
DISPLAY 1.234043 (-1700 2100);
PAINT GREEN (-1700 2100);
DISPLAY INVISIBLE (-1700 2100);
FORCEPROP 1 LAST HDL_TAP TRUE
J 2
(-2025 2025);
DISPLAY 1.234043 (-2025 2025);
PAINT GREEN (-2025 2025);
DISPLAY INVISIBLE (-2025 2025);
FORCEPROP 1 LAST PATH I96
J 2
(-1700 2150);
DISPLAY 0.936170 (-1700 2150);
PAINT GREEN (-1700 2150);
DISPLAY INVISIBLE (-1700 2150);
FORCEADD TAP..6
R 2
(-1700 2200);
FORCEPROP 3 LASTPIN (-1750 2200) SIG_NAME M_B_DQ<14>
J 0
(-1740 2210);
DISPLAY 0.659574 (-1740 2210);
PAINT MONO (-1740 2210);
DISPLAY INVISIBLE (-1740 2210);
FORCEPROP 1 LASTPIN (-1750 2200) BN 14
J 2
(-1700 2210);
DISPLAY 0.617021 (-1700 2210);
PAINT PINK (-1700 2210);
FORCEPROP 2 LAST CDS_LIB mstr_standard
J 2
(-1700 2200);
DISPLAY 0.787234 (-1700 2200);
PAINT MONO (-1700 2200);
DISPLAY INVISIBLE (-1700 2200);
FORCEPROP 1 LAST BODY_TYPE PLUMBING
J 2
(-1700 2150);
DISPLAY 1.234043 (-1700 2150);
PAINT GREEN (-1700 2150);
DISPLAY INVISIBLE (-1700 2150);
FORCEPROP 1 LAST HDL_TAP TRUE
J 2
(-2025 2075);
DISPLAY 1.234043 (-2025 2075);
PAINT GREEN (-2025 2075);
DISPLAY INVISIBLE (-2025 2075);
FORCEPROP 1 LAST PATH I97
J 2
(-1700 2200);
DISPLAY 0.936170 (-1700 2200);
PAINT GREEN (-1700 2200);
DISPLAY INVISIBLE (-1700 2200);
FORCEADD TAP..6
R 2
(-1700 2000);
FORCEPROP 3 LASTPIN (-1750 2000) SIG_NAME M_B_DQ<10>
J 0
(-1740 2010);
DISPLAY 0.659574 (-1740 2010);
PAINT MONO (-1740 2010);
DISPLAY INVISIBLE (-1740 2010);
FORCEPROP 1 LASTPIN (-1750 2000) BN 10
J 2
(-1700 2010);
DISPLAY 0.617021 (-1700 2010);
PAINT PINK (-1700 2010);
FORCEPROP 2 LAST CDS_LIB mstr_standard
J 2
(-1700 2000);
DISPLAY 0.787234 (-1700 2000);
PAINT MONO (-1700 2000);
DISPLAY INVISIBLE (-1700 2000);
FORCEPROP 1 LAST BODY_TYPE PLUMBING
J 2
(-1700 1950);
DISPLAY 1.234043 (-1700 1950);
PAINT GREEN (-1700 1950);
DISPLAY INVISIBLE (-1700 1950);
FORCEPROP 1 LAST HDL_TAP TRUE
J 2
(-2025 1875);
DISPLAY 1.234043 (-2025 1875);
PAINT GREEN (-2025 1875);
DISPLAY INVISIBLE (-2025 1875);
FORCEPROP 1 LAST PATH I98
J 2
(-1700 2000);
DISPLAY 0.936170 (-1700 2000);
PAINT GREEN (-1700 2000);
DISPLAY INVISIBLE (-1700 2000);
FORCEADD TAP..6
R 2
(-1700 2050);
FORCEPROP 3 LASTPIN (-1750 2050) SIG_NAME M_B_DQ<13>
J 0
(-1740 2060);
DISPLAY 0.659574 (-1740 2060);
PAINT MONO (-1740 2060);
DISPLAY INVISIBLE (-1740 2060);
FORCEPROP 1 LASTPIN (-1750 2050) BN 13
J 2
(-1700 2060);
DISPLAY 0.617021 (-1700 2060);
PAINT PINK (-1700 2060);
FORCEPROP 2 LAST CDS_LIB mstr_standard
J 2
(-1700 2050);
DISPLAY 0.787234 (-1700 2050);
PAINT MONO (-1700 2050);
DISPLAY INVISIBLE (-1700 2050);
FORCEPROP 1 LAST BODY_TYPE PLUMBING
J 2
(-1700 2000);
DISPLAY 1.234043 (-1700 2000);
PAINT GREEN (-1700 2000);
DISPLAY INVISIBLE (-1700 2000);
FORCEPROP 1 LAST HDL_TAP TRUE
J 2
(-2025 1925);
DISPLAY 1.234043 (-2025 1925);
PAINT GREEN (-2025 1925);
DISPLAY INVISIBLE (-2025 1925);
FORCEPROP 1 LAST PATH I99
J 2
(-1700 2050);
DISPLAY 0.936170 (-1700 2050);
PAINT GREEN (-1700 2050);
DISPLAY INVISIBLE (-1700 2050);
FORCEADD INTEL_CORP_BPAGE..1
(2650 500);
FORCEPROP 1 LAST CDS_CON_LAST_MODIFIED Fri Jun 16 17:48:17 2017
J 0
(1225 825);
DISPLAY 0.787234 (1225 825);
PAINT ORANGE (1225 825);
DISPLAY INVISIBLE (1225 825);
FORCEPROP 1 LAST CUSTOM_TXT_CDS <CURRENT_DESIGN_SHEET> OF <TOTAL_DESIGN_SHEETS>
J 0
(2150 525);
PAINT ORANGE (2150 525);
FORCEPROP 1 LAST CUSTOM_TXT_CDS <CON_LAST_MODIFIED>
J 0
(-1350 600);
PAINT ORANGE (-1350 600);
FORCEPROP 2 LAST CUSTOM_TXT_CDS <XR_PAGE_TITLE>
J 0
(-5240 5750);
DISPLAY 0.638298 (-5240 5750);
PAINT PINK (-5240 5750);
DISPLAY INVISIBLE (-5240 5750);
FORCEPROP 1 LAST SCH_TITLE CPU0 DDR4 CH B DIMM0
J 0
(-5300 550);
DISPLAY 1.212766 (-5300 550);
PAINT WHITE (-5300 550);
FORCEPROP 2 LAST PAGE_BORDER TRUE
J 0
(-5240 5750);
DISPLAY 0.680851 (-5240 5750);
PAINT PINK (-5240 5750);
DISPLAY INVISIBLE (-5240 5750);
FORCEPROP 2 LAST CDS_LIB mstr_symbols
J 0
(2650 500);
DISPLAY 0.787234 (2650 500);
PAINT MONO (2650 500);
DISPLAY INVISIBLE (2650 500);
FORCEPROP 1 LAST COMMENT_BODY TRUE
J 0
(2660 510);
DISPLAY 0.382979 (2660 510);
PAINT GREEN (2660 510);
DISPLAY INVISIBLE (2660 510);
FORCEPROP 2 LAST CDS_XR_PAGE_TITLE CR-45 : @BASEBOARD_FAB2_LIB.BASEBOARD_FAB2(SCH_1):PAGE45
J 0
(-5240 5750);
DISPLAY 0.638298 (-5240 5750);
PAINT PINK (-5240 5750);
DISPLAY INVISIBLE (-5240 5750);
FORCEADD BOM_NOTE..1
(-5000 5300);
FORCEPROP 0 LAST L1 STUFF FOR SKU A & B
J 0
(-5150 5200);
DISPLAY 1.063830 (-5150 5200);
PAINT WHITE (-5150 5200);
FORCEPROP 2 LAST CDS_LIB mstr_symbols
J 0
(-5000 5300);
PAINT ORANGE (-5000 5300);
DISPLAY INVISIBLE (-5000 5300);
FORCEPROP 2 LAST BOM_COST SB
J 0
(-5150 5275);
DISPLAY 1.361702 (-5150 5275);
PAINT ORANGE (-5150 5275);
DISPLAY INVISIBLE (-5150 5275);
FORCEPROP 1 LAST COMMENT_BODY TRUE
J 0
(-4975 5400);
DISPLAY 1.319149 (-4975 5400);
PAINT ORANGE (-4975 5400);
DISPLAY INVISIBLE (-4975 5400);
FORCEPROP 2 LAST ROOM SB_HEADERS
J 0
(-5150 5275);
DISPLAY 1.361702 (-5150 5275);
PAINT ORANGE (-5150 5275);
DISPLAY INVISIBLE (-5150 5275);
WIRE 16 -1 (-800 2650)(-800 2550);
WIRE 16 -1 (-800 2550)(-650 2550);
WIRE 16 -1 (-650 2500)(-650 2550);
WIRE 16 -1 (-650 2550)(-450 2550);
WIRE 16 -1 (-650 2500)(-450 2500);
WIRE 16 -1 (-1025 2500)(-1025 2400);
WIRE 16 -1 (-1025 2400)(-650 2400);
WIRE 16 -1 (-650 2350)(-650 2400);
WIRE 16 -1 (-650 2400)(-450 2400);
WIRE 16 -1 (-650 2300)(-650 2350);
WIRE 16 -1 (-650 2350)(-450 2350);
WIRE 16 -1 (-650 2250)(-650 2300);
WIRE 16 -1 (-650 2300)(-450 2300);
WIRE 16 -1 (-650 2200)(-650 2250);
WIRE 16 -1 (-650 2250)(-450 2250);
WIRE 16 -1 (-650 2150)(-650 2200);
WIRE 16 -1 (-650 2200)(-450 2200);
WIRE 16 -1 (-650 2100)(-650 2150);
WIRE 16 -1 (-650 2150)(-450 2150);
WIRE 16 -1 (-650 2050)(-650 2100);
WIRE 16 -1 (-650 2100)(-450 2100);
WIRE 16 -1 (-650 2000)(-650 2050);
WIRE 16 -1 (-650 2050)(-450 2050);
WIRE 16 -1 (-650 1950)(-650 2000);
WIRE 16 -1 (-650 2000)(-450 2000);
WIRE 16 -1 (-650 1900)(-650 1950);
WIRE 16 -1 (-650 1950)(-450 1950);
WIRE 16 -1 (-650 1850)(-650 1900);
WIRE 16 -1 (-650 1900)(-450 1900);
WIRE 16 -1 (-650 1800)(-650 1850);
WIRE 16 -1 (-650 1850)(-450 1850);
WIRE 16 -1 (-650 1750)(-650 1800);
WIRE 16 -1 (-650 1800)(-450 1800);
WIRE 16 -1 (-650 1700)(-650 1750);
WIRE 16 -1 (-650 1750)(-450 1750);
WIRE 16 -1 (-650 1650)(-650 1700);
WIRE 16 -1 (-650 1700)(-450 1700);
WIRE 16 -1 (-650 1600)(-650 1650);
WIRE 16 -1 (-650 1650)(-450 1650);
WIRE 16 -1 (-650 1550)(-650 1600);
WIRE 16 -1 (-650 1600)(-450 1600);
WIRE 16 -1 (-650 1500)(-650 1550);
WIRE 16 -1 (-650 1550)(-450 1550);
WIRE 16 -1 (-650 1450)(-650 1500);
WIRE 16 -1 (-650 1500)(-450 1500);
WIRE 16 -1 (-650 1400)(-650 1450);
WIRE 16 -1 (-650 1450)(-450 1450);
WIRE 16 -1 (-650 1350)(-650 1400);
WIRE 16 -1 (-650 1400)(-450 1400);
WIRE 16 -1 (-650 1300)(-650 1350);
WIRE 16 -1 (-650 1350)(-450 1350);
WIRE 16 -1 (-650 1250)(-650 1300);
WIRE 16 -1 (-650 1300)(-450 1300);
WIRE 16 -1 (-650 1200)(-650 1250);
WIRE 16 -1 (-650 1250)(-450 1250);
WIRE 16 -1 (-650 1150)(-650 1200);
WIRE 16 -1 (-650 1200)(-450 1200);
WIRE 16 -1 (-650 1150)(-450 1150);
WIRE 16 -1 (-5050 1650)(-3200 1650);
WIRE 16 -1 (-3200 1750)(-3200 1650);
WIRE 16 -1 (-3200 1650)(-2950 1650);
WIRE 16 -1 (-2950 1750)(-3200 1750);
WIRE 16 -1 (-4600 1150)(-4600 1050);
WIRE 16 -1 (-650 2950)(-650 2850);
WIRE 16 -1 (-650 2850)(-650 2800);
WIRE 16 -1 (-650 2850)(-450 2850);
WIRE 16 -1 (-650 2750)(-650 2800);
WIRE 16 -1 (-650 2800)(-450 2800);
WIRE 16 -1 (-650 2750)(-650 2700);
WIRE 16 -1 (-650 2750)(-450 2750);
WIRE 16 -1 (-650 2700)(-650 2650);
WIRE 16 -1 (-650 2700)(-450 2700);
WIRE 16 -1 (-650 2650)(-450 2650);
WIRE 16 -1 (-5050 1900)(-5050 1800);
WIRE 16 -1 (-3125 1800)(-5050 1800);
WIRE 16 -1 (-3125 1700)(-3125 1800);
WIRE 16 -1 (-2950 1800)(-3125 1800);
WIRE 16 -1 (-2950 1700)(-3125 1700);
WIRE 16 -1 (750 2850)(750 3025);
WIRE 16 -1 (750 2800)(750 2850);
WIRE 16 -1 (550 2850)(750 2850);
WIRE 16 -1 (550 2800)(750 2800);
WIRE 16 -1 (2500 1450)(2500 1350);
WIRE 16 -1 (2500 1500)(2500 1450);
WIRE 16 -1 (2500 1450)(2300 1450);
WIRE 16 -1 (2500 1550)(2500 1500);
WIRE 16 -1 (2500 1500)(2300 1500);
WIRE 16 -1 (2500 1600)(2500 1550);
WIRE 16 -1 (2500 1550)(2300 1550);
WIRE 16 -1 (2500 1650)(2500 1600);
WIRE 16 -1 (2500 1600)(2300 1600);
WIRE 16 -1 (2500 1700)(2500 1650);
WIRE 16 -1 (2500 1650)(2300 1650);
WIRE 16 -1 (2500 1750)(2500 1700);
WIRE 16 -1 (2500 1700)(2300 1700);
WIRE 16 -1 (2500 1800)(2500 1750);
WIRE 16 -1 (2500 1750)(2300 1750);
WIRE 16 -1 (2500 1850)(2500 1800);
WIRE 16 -1 (2500 1800)(2300 1800);
WIRE 16 -1 (2500 1900)(2500 1850);
WIRE 16 -1 (2500 1850)(2300 1850);
WIRE 16 -1 (2500 1950)(2500 1900);
WIRE 16 -1 (2500 1900)(2300 1900);
WIRE 16 -1 (2500 2000)(2500 1950);
WIRE 16 -1 (2500 1950)(2300 1950);
WIRE 16 -1 (2500 2050)(2500 2000);
WIRE 16 -1 (2500 2000)(2300 2000);
WIRE 16 -1 (2500 2100)(2500 2050);
WIRE 16 -1 (2500 2050)(2300 2050);
WIRE 16 -1 (2500 2150)(2500 2100);
WIRE 16 -1 (2500 2100)(2300 2100);
WIRE 16 -1 (2500 2200)(2500 2150);
WIRE 16 -1 (2500 2150)(2300 2150);
WIRE 16 -1 (2500 2250)(2500 2200);
WIRE 16 -1 (2500 2200)(2300 2200);
WIRE 16 -1 (2500 2300)(2500 2250);
WIRE 16 -1 (2500 2250)(2300 2250);
WIRE 16 -1 (2500 2350)(2500 2300);
WIRE 16 -1 (2500 2300)(2300 2300);
WIRE 16 -1 (2500 2400)(2500 2350);
WIRE 16 -1 (2500 2350)(2300 2350);
WIRE 16 -1 (2500 2450)(2500 2400);
WIRE 16 -1 (2500 2400)(2300 2400);
WIRE 16 -1 (2500 2500)(2500 2450);
WIRE 16 -1 (2500 2450)(2300 2450);
WIRE 16 -1 (2500 2550)(2500 2500);
WIRE 16 -1 (2500 2500)(2300 2500);
WIRE 16 -1 (2500 2600)(2500 2550);
WIRE 16 -1 (2500 2550)(2300 2550);
WIRE 16 -1 (2500 2650)(2500 2600);
WIRE 16 -1 (2500 2600)(2300 2600);
WIRE 16 -1 (2500 2700)(2500 2650);
WIRE 16 -1 (2500 2650)(2300 2650);
WIRE 16 -1 (2500 2750)(2500 2700);
WIRE 16 -1 (2500 2700)(2300 2700);
WIRE 16 -1 (2500 2800)(2500 2750);
WIRE 16 -1 (2500 2750)(2300 2750);
WIRE 16 -1 (2500 2850)(2500 2800);
WIRE 16 -1 (2500 2800)(2300 2800);
WIRE 16 -1 (2500 2900)(2500 2850);
WIRE 16 -1 (2500 2850)(2300 2850);
WIRE 16 -1 (2500 2950)(2500 2900);
WIRE 16 -1 (2500 2900)(2300 2900);
WIRE 16 -1 (2500 3000)(2500 2950);
WIRE 16 -1 (2500 2950)(2300 2950);
WIRE 16 -1 (2500 3050)(2500 3000);
WIRE 16 -1 (2500 3000)(2300 3000);
WIRE 16 -1 (2500 3050)(2500 3100);
WIRE 16 -1 (2500 3050)(2300 3050);
WIRE 16 -1 (2500 3150)(2500 3100);
WIRE 16 -1 (2500 3100)(2300 3100);
WIRE 16 -1 (2500 3150)(2500 3200);
WIRE 16 -1 (2500 3150)(2300 3150);
WIRE 16 -1 (2500 3200)(2500 3250);
WIRE 16 -1 (2500 3200)(2300 3200);
WIRE 16 -1 (2500 3250)(2500 3300);
WIRE 16 -1 (2500 3250)(2300 3250);
WIRE 16 -1 (2500 3300)(2500 3350);
WIRE 16 -1 (2500 3300)(2300 3300);
WIRE 16 -1 (2500 3350)(2500 3400);
WIRE 16 -1 (2500 3350)(2300 3350);
WIRE 16 -1 (2500 3400)(2500 3450);
WIRE 16 -1 (2500 3400)(2300 3400);
WIRE 16 -1 (2500 3450)(2500 3500);
WIRE 16 -1 (2500 3450)(2300 3450);
WIRE 16 -1 (2500 3500)(2500 3550);
WIRE 16 -1 (2500 3500)(2300 3500);
WIRE 16 -1 (2500 3550)(2500 3600);
WIRE 16 -1 (2500 3550)(2300 3550);
WIRE 16 -1 (2500 3600)(2500 3650);
WIRE 16 -1 (2500 3600)(2300 3600);
WIRE 16 -1 (2500 3650)(2500 3700);
WIRE 16 -1 (2500 3650)(2300 3650);
WIRE 16 -1 (2500 3700)(2500 3750);
WIRE 16 -1 (2500 3700)(2300 3700);
WIRE 16 -1 (2500 3750)(2300 3750);
WIRE 16 -1 (1100 1350)(1100 1450);
WIRE 16 -1 (1100 1450)(1100 1500);
WIRE 16 -1 (1100 1450)(1300 1450);
WIRE 16 -1 (1100 1500)(1100 1550);
WIRE 16 -1 (1100 1500)(1300 1500);
WIRE 16 -1 (1100 1550)(1100 1600);
WIRE 16 -1 (1100 1550)(1300 1550);
WIRE 16 -1 (1100 1600)(1100 1650);
WIRE 16 -1 (1100 1600)(1300 1600);
WIRE 16 -1 (1100 1650)(1100 1700);
WIRE 16 -1 (1100 1650)(1300 1650);
WIRE 16 -1 (1100 1700)(1100 1750);
WIRE 16 -1 (1100 1700)(1300 1700);
WIRE 16 -1 (1100 1750)(1100 1800);
WIRE 16 -1 (1100 1750)(1300 1750);
WIRE 16 -1 (1100 1800)(1100 1850);
WIRE 16 -1 (1100 1800)(1300 1800);
WIRE 16 -1 (1100 1850)(1100 1900);
WIRE 16 -1 (1100 1850)(1300 1850);
WIRE 16 -1 (1100 1900)(1100 1950);
WIRE 16 -1 (1100 1900)(1300 1900);
WIRE 16 -1 (1100 1950)(1100 2000);
WIRE 16 -1 (1100 1950)(1300 1950);
WIRE 16 -1 (1100 2000)(1100 2050);
WIRE 16 -1 (1100 2000)(1300 2000);
WIRE 16 -1 (1100 2050)(1100 2100);
WIRE 16 -1 (1100 2050)(1300 2050);
WIRE 16 -1 (1100 2100)(1100 2150);
WIRE 16 -1 (1100 2100)(1300 2100);
WIRE 16 -1 (1100 2150)(1100 2200);
WIRE 16 -1 (1100 2150)(1300 2150);
WIRE 16 -1 (1100 2200)(1100 2250);
WIRE 16 -1 (1100 2200)(1300 2200);
WIRE 16 -1 (1100 2250)(1100 2300);
WIRE 16 -1 (1100 2250)(1300 2250);
WIRE 16 -1 (1100 2300)(1100 2350);
WIRE 16 -1 (1100 2300)(1300 2300);
WIRE 16 -1 (1100 2350)(1100 2400);
WIRE 16 -1 (1100 2350)(1300 2350);
WIRE 16 -1 (1100 2400)(1100 2450);
WIRE 16 -1 (1100 2400)(1300 2400);
WIRE 16 -1 (1100 2450)(1100 2500);
WIRE 16 -1 (1100 2450)(1300 2450);
WIRE 16 -1 (1100 2500)(1100 2550);
WIRE 16 -1 (1100 2500)(1300 2500);
WIRE 16 -1 (1100 2550)(1100 2600);
WIRE 16 -1 (1100 2550)(1300 2550);
WIRE 16 -1 (1100 2600)(1100 2650);
WIRE 16 -1 (1100 2600)(1300 2600);
WIRE 16 -1 (1100 2650)(1100 2700);
WIRE 16 -1 (1100 2650)(1300 2650);
WIRE 16 -1 (1100 2700)(1100 2750);
WIRE 16 -1 (1100 2700)(1300 2700);
WIRE 16 -1 (1100 2750)(1100 2800);
WIRE 16 -1 (1100 2750)(1300 2750);
WIRE 16 -1 (1100 2800)(1100 2850);
WIRE 16 -1 (1100 2800)(1300 2800);
WIRE 16 -1 (1100 2850)(1100 2900);
WIRE 16 -1 (1100 2850)(1300 2850);
WIRE 16 -1 (1100 2900)(1100 2950);
WIRE 16 -1 (1100 2900)(1300 2900);
WIRE 16 -1 (1100 2950)(1100 3000);
WIRE 16 -1 (1100 2950)(1300 2950);
WIRE 16 -1 (1100 3000)(1100 3050);
WIRE 16 -1 (1100 3000)(1300 3000);
WIRE 16 -1 (1100 3050)(1100 3100);
WIRE 16 -1 (1100 3050)(1300 3050);
WIRE 16 -1 (1100 3100)(1100 3150);
WIRE 16 -1 (1100 3100)(1300 3100);
WIRE 16 -1 (1100 3150)(1100 3200);
WIRE 16 -1 (1100 3150)(1300 3150);
WIRE 16 -1 (1100 3200)(1100 3250);
WIRE 16 -1 (1100 3200)(1300 3200);
WIRE 16 -1 (1100 3250)(1100 3300);
WIRE 16 -1 (1100 3250)(1300 3250);
WIRE 16 -1 (1100 3300)(1100 3350);
WIRE 16 -1 (1100 3300)(1300 3300);
WIRE 16 -1 (1100 3350)(1100 3400);
WIRE 16 -1 (1100 3350)(1300 3350);
WIRE 16 -1 (1100 3400)(1100 3450);
WIRE 16 -1 (1100 3400)(1300 3400);
WIRE 16 -1 (1100 3450)(1100 3500);
WIRE 16 -1 (1100 3450)(1300 3450);
WIRE 16 -1 (1100 3500)(1100 3550);
WIRE 16 -1 (1100 3500)(1300 3500);
WIRE 16 -1 (1100 3550)(1100 3600);
WIRE 16 -1 (1100 3550)(1300 3550);
WIRE 16 -1 (1100 3600)(1100 3650);
WIRE 16 -1 (1100 3600)(1300 3600);
WIRE 16 -1 (1100 3650)(1100 3700);
WIRE 16 -1 (1100 3650)(1300 3650);
WIRE 16 -1 (1100 3700)(1100 3750);
WIRE 16 -1 (1100 3700)(1300 3700);
WIRE 16 -1 (1100 3750)(1300 3750);
WIRE 17 -1 (750 3475)(750 3575);
WIRE 17 -1 (750 3575)(750 3675);
WIRE 17 -1 (750 3675)(750 3775);
WIRE 17 -1 (750 3775)(750 3875);
WIRE 17 -1 (750 3875)(750 3975);
WIRE 17 -1 (750 3975)(750 4075);
WIRE 17 -1 (750 4075)(750 4175);
WIRE 17 -1 (750 4175)(750 4275);
WIRE 17 -1 (750 4275)(750 4375);
WIRE 17 -1 (750 4375)(750 4475);
WIRE 17 -1 (750 4475)(750 4575);
WIRE 17 -1 (750 4575)(750 4675);
WIRE 17 -1 (750 4675)(750 4775);
WIRE 17 -1 (750 4775)(750 4875);
WIRE 17 -1 (750 4875)(750 4975);
WIRE 17 -1 (1550 5200)(750 5200);
FORCEPROP 2 LAST SIG_NAME M_B_DQS_DP<17:0>
J 0
(1000 5210);
DISPLAY 0.617021 (1000 5210);
PAINT ORANGE (1000 5210);
WIRE 17 -1 (750 5175)(750 5200);
WIRE 17 -1 (750 4975)(750 5075);
WIRE 17 -1 (750 5075)(750 5175);
WIRE 17 -1 (950 3425)(950 3525);
WIRE 17 -1 (950 3525)(950 3625);
WIRE 17 -1 (950 3625)(950 3725);
WIRE 17 -1 (1550 5150)(950 5150);
FORCEPROP 2 LAST SIG_NAME M_B_DQS_DN<17:0>
J 0
(1000 5160);
DISPLAY 0.617021 (1000 5160);
PAINT ORANGE (1000 5160);
WIRE 17 -1 (950 5125)(950 5150);
WIRE 17 -1 (950 3725)(950 3825);
WIRE 17 -1 (950 3825)(950 3925);
WIRE 17 -1 (950 5025)(950 5125);
WIRE 17 -1 (950 4925)(950 5025);
WIRE 17 -1 (950 3925)(950 4025);
WIRE 17 -1 (950 4025)(950 4125);
WIRE 17 -1 (950 4825)(950 4925);
WIRE 17 -1 (950 4725)(950 4825);
WIRE 17 -1 (950 4125)(950 4225);
WIRE 17 -1 (950 4225)(950 4325);
WIRE 17 -1 (950 4625)(950 4725);
WIRE 17 -1 (950 4525)(950 4625);
WIRE 17 -1 (950 4325)(950 4425);
WIRE 17 -1 (950 4425)(950 4525);
WIRE 17 -1 (-1650 1475)(-1650 1525);
WIRE 17 -1 (-1650 1525)(-1650 1575);
WIRE 17 -1 (-1650 1575)(-1650 1625);
WIRE 17 -1 (-1650 1625)(-1650 1675);
WIRE 17 -1 (-1650 1675)(-1650 1725);
WIRE 17 -1 (-1650 1725)(-1650 1775);
WIRE 17 -1 (-1650 1775)(-1650 1825);
WIRE 17 -1 (-1650 1825)(-1650 1875);
WIRE 17 -1 (-1650 1875)(-1650 1925);
WIRE 17 -1 (-1650 1925)(-1650 1975);
WIRE 17 -1 (-1650 1975)(-1650 2025);
WIRE 17 -1 (-1650 2025)(-1650 2075);
WIRE 17 -1 (-1650 2075)(-1650 2125);
WIRE 17 -1 (-1650 2125)(-1650 2175);
WIRE 17 -1 (-1650 2175)(-1650 2225);
WIRE 17 -1 (-1650 2225)(-1650 2275);
WIRE 17 -1 (-1650 2275)(-1650 2325);
WIRE 17 -1 (-1650 2325)(-1650 2375);
WIRE 17 -1 (-1650 2375)(-1650 2425);
WIRE 17 -1 (-1650 2425)(-1650 2475);
WIRE 17 -1 (-1650 2475)(-1650 2525);
WIRE 17 -1 (-1650 2525)(-1650 2575);
WIRE 17 -1 (-1650 2575)(-1650 2625);
WIRE 17 -1 (-1650 2625)(-1650 2675);
WIRE 17 -1 (-1650 2675)(-1650 2725);
WIRE 17 -1 (-1650 2725)(-1650 2775);
WIRE 17 -1 (-1650 2775)(-1650 2825);
WIRE 17 -1 (-1650 2825)(-1650 2875);
WIRE 17 -1 (-1650 2875)(-1650 2925);
WIRE 17 -1 (-1650 2925)(-1650 2975);
WIRE 17 -1 (-1650 2975)(-1650 3025);
WIRE 17 -1 (-1650 3025)(-1650 3075);
WIRE 17 -1 (-1650 3075)(-1650 3125);
WIRE 17 -1 (-1650 3125)(-1650 3175);
WIRE 17 -1 (-1650 3175)(-1650 3225);
WIRE 17 -1 (-1650 3225)(-1650 3275);
WIRE 17 -1 (-1650 3275)(-1650 3325);
WIRE 17 -1 (-1650 3325)(-1650 3375);
WIRE 17 -1 (-1650 3375)(-1650 3425);
WIRE 17 -1 (-1650 3425)(-1650 3475);
WIRE 17 -1 (-1650 3475)(-1650 3525);
WIRE 17 -1 (-1650 3525)(-1650 3575);
WIRE 17 -1 (-1650 3575)(-1650 3625);
WIRE 17 -1 (-1650 3625)(-1650 3675);
WIRE 17 -1 (-1650 3675)(-1650 3725);
WIRE 17 -1 (-1650 3725)(-1650 3775);
WIRE 17 -1 (-1650 3775)(-1650 3825);
WIRE 17 -1 (-1650 3825)(-1650 3875);
WIRE 17 -1 (-1650 3875)(-1650 3925);
WIRE 17 -1 (-1650 3925)(-1650 3975);
WIRE 17 -1 (-1650 3975)(-1650 4025);
WIRE 17 -1 (-1650 4025)(-1650 4075);
WIRE 17 -1 (-1650 4075)(-1650 4125);
WIRE 17 -1 (-1650 4125)(-1650 4175);
WIRE 17 -1 (-1200 4650)(-1650 4650);
FORCEPROP 2 LAST SIG_NAME M_B_DQ<63:0>
J 0
(-1610 4660);
DISPLAY 0.617021 (-1610 4660);
PAINT ORANGE (-1610 4660);
WIRE 17 -1 (-1650 4175)(-1650 4225);
WIRE 17 -1 (-1650 4225)(-1650 4275);
WIRE 17 -1 (-1650 4625)(-1650 4650);
WIRE 17 -1 (-1650 4575)(-1650 4625);
WIRE 17 -1 (-1650 4275)(-1650 4325);
WIRE 17 -1 (-1650 4325)(-1650 4375);
WIRE 17 -1 (-1650 4525)(-1650 4575);
WIRE 17 -1 (-1650 4475)(-1650 4525);
WIRE 17 -1 (-1650 4375)(-1650 4425);
WIRE 17 -1 (-1650 4425)(-1650 4475);
WIRE 17 -1 (-3250 3775)(-3250 3825);
WIRE 17 -1 (-3250 3825)(-3250 3875);
WIRE 17 -1 (-3250 3875)(-3250 3925);
WIRE 17 -1 (-3250 3925)(-3250 3975);
WIRE 17 -1 (-3800 4650)(-3250 4650);
FORCEPROP 2 LAST SIG_NAME M_B_MA<17:0>
J 0
(-3750 4660);
DISPLAY 0.617021 (-3750 4660);
PAINT ORANGE (-3750 4660);
WIRE 17 -1 (-3250 3975)(-3250 4025);
WIRE 17 -1 (-3250 4025)(-3250 4075);
WIRE 17 -1 (-3250 4625)(-3250 4650);
WIRE 17 -1 (-3250 4575)(-3250 4625);
WIRE 17 -1 (-3250 4075)(-3250 4125);
WIRE 17 -1 (-3250 4125)(-3250 4175);
WIRE 17 -1 (-3250 4525)(-3250 4575);
WIRE 17 -1 (-3250 4475)(-3250 4525);
WIRE 17 -1 (-3250 4175)(-3250 4225);
WIRE 17 -1 (-3250 4225)(-3250 4275);
WIRE 17 -1 (-3250 4425)(-3250 4475);
WIRE 17 -1 (-3250 4375)(-3250 4425);
WIRE 17 -1 (-3250 4275)(-3250 4325);
WIRE 17 -1 (-3250 4325)(-3250 4375);
WIRE 17 -1 (-3250 3600)(-3800 3600);
FORCEPROP 2 LAST SIG_NAME M_B_BG<1:0>
J 0
(-3750 3610);
DISPLAY 0.617021 (-3750 3610);
PAINT ORANGE (-3750 3610);
WIRE 17 -1 (-3250 3575)(-3250 3600);
WIRE 17 -1 (-3250 3525)(-3250 3575);
WIRE 17 -1 (-3450 3450)(-3950 3450);
FORCEPROP 2 LAST SIG_NAME M_B_CLK_DN<3:0>
J 0
(-3900 3460);
DISPLAY 0.617021 (-3900 3460);
PAINT ORANGE (-3900 3460);
WIRE 17 -1 (-3450 3375)(-3450 3275);
WIRE 17 -1 (-3450 3375)(-3450 3450);
WIRE 17 -1 (-3250 2600)(-3800 2600);
FORCEPROP 2 LAST SIG_NAME M_B_ECC<7:0>
J 0
(-3775 2610);
DISPLAY 0.617021 (-3775 2610);
PAINT ORANGE (-3775 2610);
WIRE 17 -1 (-3250 2575)(-3250 2600);
WIRE 17 -1 (-3250 2525)(-3250 2575);
WIRE 17 -1 (-3250 2475)(-3250 2525);
WIRE 17 -1 (-3250 2425)(-3250 2475);
WIRE 17 -1 (-3250 2375)(-3250 2425);
WIRE 17 -1 (-3250 2325)(-3250 2375);
WIRE 17 -1 (-3250 2275)(-3250 2325);
WIRE 17 -1 (-3250 2225)(-3250 2275);
WIRE 17 -1 (-3250 3625)(-3250 3675);
WIRE 17 -1 (-3250 3700)(-3800 3700);
FORCEPROP 2 LAST SIG_NAME M_B_BA<1:0>
J 0
(-3750 3710);
DISPLAY 0.617021 (-3750 3710);
PAINT ORANGE (-3750 3710);
WIRE 17 -1 (-3250 3700)(-3250 3675);
WIRE 17 -1 (-3250 3500)(-3950 3500);
FORCEPROP 2 LAST SIG_NAME M_B_CLK_DP<3:0>
J 0
(-3900 3510);
DISPLAY 0.617021 (-3900 3510);
PAINT ORANGE (-3900 3510);
WIRE 17 -1 (-3250 3425)(-3250 3500);
WIRE 17 -1 (-3250 3325)(-3250 3425);
WIRE 17 -1 (-3250 2975)(-3250 3025);
WIRE 17 -1 (-3250 3150)(-3800 3150);
FORCEPROP 2 LAST SIG_NAME M_B_CS_N<7:0>
J 0
(-3750 3160);
DISPLAY 0.617021 (-3750 3160);
PAINT ORANGE (-3750 3160);
WIRE 17 -1 (-3250 3125)(-3250 3150);
WIRE 17 -1 (-3250 3025)(-3250 3075);
WIRE 17 -1 (-3250 3075)(-3250 3125);
WIRE 17 -1 (-3250 2950)(-3800 2950);
FORCEPROP 2 LAST SIG_NAME M_B_CKE<3:0>
J 0
(-3775 2960);
DISPLAY 0.617021 (-3775 2960);
PAINT ORANGE (-3775 2960);
WIRE 17 -1 (-3250 2825)(-3250 2875);
WIRE 17 -1 (-3250 2875)(-3250 2950);
WIRE 17 -1 (-3250 2800)(-3800 2800);
FORCEPROP 2 LAST SIG_NAME M_B_ODT<3:0>
J 0
(-3775 2810);
DISPLAY 0.617021 (-3775 2810);
PAINT ORANGE (-3775 2810);
WIRE 17 -1 (-3250 2725)(-3250 2800);
WIRE 17 -1 (-3250 2675)(-3250 2725);
WIRE 16 -1 (650 4450)(450 4450);
WIRE 16 -1 (650 4350)(450 4350);
WIRE 16 -1 (850 4400)(450 4400);
WIRE 16 -1 (-1750 4350)(-1950 4350);
WIRE 16 -1 (850 4900)(450 4900);
WIRE 16 -1 (650 4750)(450 4750);
WIRE 16 -1 (-3400 2300)(-4125 2300);
FORCEPROP 2 LAST SIG_NAME FM_DIMM_EVENT_COD_N
J 0
(-4077 2322);
DISPLAY 0.617021 (-4077 2322);
PAINT ORANGE (-4077 2322);
WIRE 16 -1 (-3400 2000)(-2950 2000);
WIRE 16 -1 (-3400 2000)(-3400 2300);
WIRE 16 -1 (-4700 1450)(-4600 1450);
WIRE 16 -1 (-2950 1450)(-4600 1450);
FORCEPROP 2 LAST SIG_NAME M_B_VREF
J 0
(-3750 1460);
DISPLAY 0.617021 (-3750 1460);
PAINT ORANGE (-3750 1460);
WIRE 16 -1 (-4600 1350)(-4600 1450);
WIRE 16 -1 (-3800 1300)(-2950 1300);
FORCEPROP 2 LAST SIG_NAME TP_CH_B_DIMM_B0_RFU_1
J 0
(-3750 1310);
DISPLAY 0.617021 (-3750 1310);
PAINT ORANGE (-3750 1310);
FORCEPROP 2 LASTPROP $XRERR UNIQUE?
J 0
(-4040 1300);
DISPLAY 0.638298 (-4040 1300);
PAINT MONO (-4040 1300);
DISPLAY INVISIBLE (-4040 1300);
WIRE 16 -1 (-3800 1250)(-2950 1250);
FORCEPROP 2 LAST SIG_NAME TP_CH_B_DIMM_B0_RFU_0
J 0
(-3750 1260);
DISPLAY 0.617021 (-3750 1260);
PAINT ORANGE (-3750 1260);
FORCEPROP 2 LASTPROP $XRERR UNIQUE?
J 0
(-4040 1250);
DISPLAY 0.638298 (-4040 1250);
PAINT MONO (-4040 1250);
DISPLAY INVISIBLE (-4040 1250);
WIRE 16 -1 (-3800 1350)(-2950 1350);
FORCEPROP 2 LAST SIG_NAME TP_CH_B_DIMM_B0_RFU_2
J 0
(-3750 1360);
DISPLAY 0.617021 (-3750 1360);
PAINT ORANGE (-3750 1360);
FORCEPROP 2 LASTPROP $XRERR UNIQUE?
J 0
(-4040 1350);
DISPLAY 0.638298 (-4040 1350);
PAINT MONO (-4040 1350);
DISPLAY INVISIBLE (-4040 1350);
WIRE 16 -1 (-2950 1950)(-3975 1950);
FORCEPROP 2 LAST SIG_NAME M_B_ALERT_N
J 0
(-3925 1960);
DISPLAY 0.617021 (-3925 1960);
PAINT ORANGE (-3925 1960);
WIRE 16 -1 (-2950 1900)(-3950 1900);
FORCEPROP 2 LAST SIG_NAME M_B_ACT_N
J 0
(-3900 1910);
DISPLAY 0.617021 (-3900 1910);
PAINT ORANGE (-3900 1910);
WIRE 16 -1 (-2950 1600)(-3800 1600);
WIRE 16 -1 (-3800 1550)(-2950 1550);
FORCEPROP 2 LAST SIG_NAME SMB_DDR_ABC_VPP_SCL
J 0
(-3760 1560);
DISPLAY 0.617021 (-3760 1560);
PAINT ORANGE (-3760 1560);
WIRE 16 -1 (-3800 1150)(-2950 1150);
FORCEPROP 2 LAST SIG_NAME FM_ADR_COMPLETE_ABC_N
J 0
(-3750 1160);
DISPLAY 0.617021 (-3750 1160);
PAINT ORANGE (-3750 1160);
WIRE 16 -1 (-3350 2500)(-3800 2500);
FORCEPROP 2 LAST SIG_NAME M_ABC_RST_N
J 0
(-3775 2510);
DISPLAY 0.617021 (-3775 2510);
PAINT ORANGE (-3775 2510);
WIRE 16 -1 (-3350 2050)(-3350 2500);
WIRE 16 -1 (-2950 2050)(-3350 2050);
WIRE 16 -1 (-3300 2550)(-3800 2550);
FORCEPROP 2 LAST SIG_NAME M_B_PAR
J 0
(-3775 2560);
DISPLAY 0.617021 (-3775 2560);
PAINT ORANGE (-3775 2560);
WIRE 16 -1 (-3300 2100)(-3300 2550);
WIRE 16 -1 (-2950 2100)(-3300 2100);
WIRE 16 -1 (-3100 3200)(-3800 3200);
FORCEPROP 2 LAST SIG_NAME M_B_C<2>
J 0
(-3750 3210);
DISPLAY 0.617021 (-3750 3210);
PAINT ORANGE (-3750 3210);
WIRE 16 -1 (-3100 3200)(-3100 3150);
WIRE 16 -1 (-3100 3150)(-2950 3150);
WIRE 16 -1 (-2950 2950)(-3150 2950);
WIRE 16 -1 (-2950 2800)(-3150 2800);
WIRE 16 -1 (-2950 2700)(-3150 2700);
WIRE 16 -1 (-2950 2650)(-3150 2650);
WIRE 16 -1 (-2950 2550)(-3150 2550);
WIRE 16 -1 (-2950 3850)(-3150 3850);
WIRE 16 -1 (-2950 3600)(-3150 3600);
WIRE 16 -1 (-2950 3550)(-3150 3550);
WIRE 16 -1 (-2950 3400)(-3150 3400);
WIRE 16 -1 (-2950 2850)(-3150 2850);
WIRE 16 -1 (-2950 2250)(-3150 2250);
WIRE 16 -1 (-2950 2300)(-3150 2300);
WIRE 16 -1 (-2950 2350)(-3150 2350);
WIRE 16 -1 (-2950 2400)(-3150 2400);
WIRE 16 -1 (-2950 2450)(-3150 2450);
WIRE 16 -1 (-2950 2500)(-3150 2500);
WIRE 16 -1 (-2950 4050)(-3150 4050);
WIRE 16 -1 (-2950 4000)(-3150 4000);
WIRE 16 -1 (-2950 3950)(-3150 3950);
WIRE 16 -1 (-2950 3900)(-3150 3900);
WIRE 16 -1 (-2950 3800)(-3150 3800);
WIRE 16 -1 (-2950 3750)(-3150 3750);
WIRE 16 -1 (-2950 3000)(-3150 3000);
WIRE 16 -1 (-2950 3050)(-3150 3050);
WIRE 16 -1 (-2950 3100)(-3150 3100);
WIRE 16 -1 (-2950 3300)(-3150 3300);
WIRE 16 -1 (-2950 3650)(-3150 3650);
WIRE 16 -1 (-2950 2200)(-3150 2200);
WIRE 16 -1 (-2950 3250)(-3350 3250);
WIRE 16 -1 (-2950 3350)(-3350 3350);
WIRE 16 -1 (-2950 3500)(-3150 3500);
WIRE 16 -1 (-1750 1450)(-1950 1450);
WIRE 16 -1 (-1750 1500)(-1950 1500);
WIRE 16 -1 (-1750 1700)(-1950 1700);
WIRE 16 -1 (-1750 1650)(-1950 1650);
WIRE 16 -1 (-1750 1600)(-1950 1600);
WIRE 16 -1 (-1750 1550)(-1950 1550);
WIRE 16 -1 (-1750 1750)(-1950 1750);
WIRE 16 -1 (-1750 1850)(-1950 1850);
WIRE 16 -1 (-1750 1900)(-1950 1900);
WIRE 16 -1 (-1750 1950)(-1950 1950);
WIRE 16 -1 (-1750 2000)(-1950 2000);
WIRE 16 -1 (-1750 1800)(-1950 1800);
WIRE 16 -1 (-1750 2300)(-1950 2300);
WIRE 16 -1 (-1750 2200)(-1950 2200);
WIRE 16 -1 (-1750 2050)(-1950 2050);
WIRE 16 -1 (-1750 2100)(-1950 2100);
WIRE 16 -1 (-1750 2150)(-1950 2150);
WIRE 16 -1 (-1750 2250)(-1950 2250);
WIRE 16 -1 (-1750 2350)(-1950 2350);
WIRE 16 -1 (-1750 2400)(-1950 2400);
WIRE 16 -1 (-1750 2500)(-1950 2500);
WIRE 16 -1 (-1750 2550)(-1950 2550);
WIRE 16 -1 (-1750 2450)(-1950 2450);
WIRE 16 -1 (-1750 2750)(-1950 2750);
WIRE 16 -1 (-1750 2800)(-1950 2800);
WIRE 16 -1 (-1750 2600)(-1950 2600);
WIRE 16 -1 (-1750 2650)(-1950 2650);
WIRE 16 -1 (-1750 2700)(-1950 2700);
WIRE 16 -1 (-1750 2950)(-1950 2950);
WIRE 16 -1 (-1750 3000)(-1950 3000);
WIRE 16 -1 (-1750 3050)(-1950 3050);
WIRE 16 -1 (-1750 2850)(-1950 2850);
WIRE 16 -1 (-1750 2900)(-1950 2900);
WIRE 16 -1 (-1750 3350)(-1950 3350);
WIRE 16 -1 (-1750 3250)(-1950 3250);
WIRE 16 -1 (-1750 3200)(-1950 3200);
WIRE 16 -1 (-1750 3100)(-1950 3100);
WIRE 16 -1 (-1750 3150)(-1950 3150);
WIRE 16 -1 (-1750 3300)(-1950 3300);
WIRE 16 -1 (-1750 3400)(-1950 3400);
WIRE 16 -1 (-1750 3450)(-1950 3450);
WIRE 16 -1 (-1750 3500)(-1950 3500);
WIRE 16 -1 (-1750 3550)(-1950 3550);
WIRE 16 -1 (-1750 3800)(-1950 3800);
WIRE 16 -1 (-1750 3850)(-1950 3850);
WIRE 16 -1 (-1750 3900)(-1950 3900);
WIRE 16 -1 (-1750 3950)(-1950 3950);
WIRE 16 -1 (-1750 4000)(-1950 4000);
WIRE 16 -1 (-1750 4050)(-1950 4050);
WIRE 16 -1 (-1750 3600)(-1950 3600);
WIRE 16 -1 (-1750 3650)(-1950 3650);
WIRE 16 -1 (-1750 3700)(-1950 3700);
WIRE 16 -1 (-1750 3750)(-1950 3750);
WIRE 16 -1 (-2950 4550)(-3150 4550);
WIRE 16 -1 (-2950 4500)(-3150 4500);
WIRE 16 -1 (-2950 4450)(-3150 4450);
WIRE 16 -1 (-2950 4300)(-3150 4300);
WIRE 16 -1 (-2950 4250)(-3150 4250);
WIRE 16 -1 (-2950 4200)(-3150 4200);
WIRE 16 -1 (-2950 4150)(-3150 4150);
WIRE 16 -1 (-2950 4100)(-3150 4100);
WIRE 16 -1 (-2950 4600)(-3150 4600);
WIRE 16 -1 (-2950 4400)(-3150 4400);
WIRE 16 -1 (-2950 4350)(-3150 4350);
WIRE 16 -1 (-1750 4600)(-1950 4600);
WIRE 16 -1 (-1750 4550)(-1950 4550);
WIRE 16 -1 (-1750 4500)(-1950 4500);
WIRE 16 -1 (-1750 4100)(-1950 4100);
WIRE 16 -1 (-1750 4150)(-1950 4150);
WIRE 16 -1 (-1750 4300)(-1950 4300);
WIRE 16 -1 (-1750 4200)(-1950 4200);
WIRE 16 -1 (-1750 4250)(-1950 4250);
WIRE 16 -1 (-1750 4400)(-1950 4400);
WIRE 16 -1 (-1750 4450)(-1950 4450);
WIRE 16 -1 (650 4050)(450 4050);
WIRE 16 -1 (850 4000)(450 4000);
WIRE 16 -1 (650 3950)(450 3950);
WIRE 16 -1 (850 3900)(450 3900);
WIRE 16 -1 (650 3850)(450 3850);
WIRE 16 -1 (850 3800)(450 3800);
WIRE 16 -1 (650 3750)(450 3750);
WIRE 16 -1 (850 3700)(450 3700);
WIRE 16 -1 (450 3650)(650 3650);
WIRE 16 -1 (450 3600)(850 3600);
WIRE 16 -1 (450 3550)(650 3550);
WIRE 16 -1 (450 3500)(850 3500);
WIRE 16 -1 (450 3450)(650 3450);
WIRE 16 -1 (450 3400)(850 3400);
WIRE 16 -1 (850 4300)(450 4300);
WIRE 16 -1 (650 4250)(450 4250);
WIRE 16 -1 (850 4200)(450 4200);
WIRE 16 -1 (650 4150)(450 4150);
WIRE 16 -1 (850 4100)(450 4100);
WIRE 16 -1 (850 5100)(450 5100);
WIRE 16 -1 (650 5050)(450 5050);
WIRE 16 -1 (850 5000)(450 5000);
WIRE 16 -1 (650 4950)(450 4950);
WIRE 16 -1 (650 4850)(450 4850);
WIRE 16 -1 (850 4800)(450 4800);
WIRE 16 -1 (850 4700)(450 4700);
WIRE 16 -1 (650 4650)(450 4650);
WIRE 16 -1 (850 4600)(450 4600);
WIRE 16 -1 (650 4550)(450 4550);
WIRE 16 -1 (850 4500)(450 4500);
WIRE 16 -1 (650 5150)(450 5150);
DOT 1 (2500 2950);
DOT 1 (1100 1650);
DOT 1 (-650 2350);
DOT 1 (-650 2800);
DOT 1 (-650 2700);
DOT 1 (-650 2100);
DOT 1 (-650 2400);
DOT 1 (750 2850);
DOT 1 (1100 3600);
DOT 1 (-3125 1800);
DOT 1 (1100 2500);
DOT 1 (2500 2750);
DOT 1 (2500 3200);
DOT 1 (2500 3250);
DOT 1 (-4600 1450);
DOT 1 (2500 2850);
DOT 1 (1100 1450);
DOT 1 (1100 1500);
DOT 1 (1100 1550);
DOT 1 (1100 1600);
DOT 1 (1100 1700);
DOT 1 (1100 1750);
DOT 1 (1100 1800);
DOT 1 (1100 1850);
DOT 1 (1100 1900);
DOT 1 (1100 1950);
DOT 1 (1100 2000);
DOT 1 (1100 2050);
DOT 1 (1100 2100);
DOT 1 (1100 2150);
DOT 1 (1100 2200);
DOT 1 (1100 2250);
DOT 1 (1100 2300);
DOT 1 (1100 2350);
DOT 1 (1100 2400);
DOT 1 (1100 2450);
DOT 1 (1100 2600);
DOT 1 (1100 2650);
DOT 1 (1100 2700);
DOT 1 (1100 2750);
DOT 1 (1100 2850);
DOT 1 (1100 2800);
DOT 1 (1100 2900);
DOT 1 (1100 2950);
DOT 1 (1100 3000);
DOT 1 (1100 3100);
DOT 1 (1100 3050);
DOT 1 (1100 3150);
DOT 1 (1100 3200);
DOT 1 (1100 3250);
DOT 1 (1100 3350);
DOT 1 (1100 3300);
DOT 1 (2500 1450);
DOT 1 (2500 1500);
DOT 1 (2500 1550);
DOT 1 (2500 1600);
DOT 1 (2500 1650);
DOT 1 (2500 1700);
DOT 1 (2500 1750);
DOT 1 (2500 1800);
DOT 1 (2500 1850);
DOT 1 (2500 1950);
DOT 1 (2500 1900);
DOT 1 (2500 2000);
DOT 1 (2500 2050);
DOT 1 (2500 2100);
DOT 1 (2500 2150);
DOT 1 (2500 2200);
DOT 1 (2500 2250);
DOT 1 (2500 2300);
DOT 1 (2500 2350);
DOT 1 (2500 2400);
DOT 1 (2500 2450);
DOT 1 (2500 2500);
DOT 1 (2500 2550);
DOT 1 (2500 2600);
DOT 1 (2500 2650);
DOT 1 (2500 2700);
DOT 1 (2500 2800);
DOT 1 (2500 2900);
DOT 1 (2500 3000);
DOT 1 (2500 3100);
DOT 1 (2500 3050);
DOT 1 (2500 3150);
DOT 1 (2500 3350);
DOT 1 (2500 3300);
DOT 1 (2500 3400);
DOT 1 (1100 3400);
DOT 1 (1100 3450);
DOT 1 (1100 3500);
DOT 1 (1100 3550);
DOT 1 (1100 3650);
DOT 1 (1100 3700);
DOT 1 (2500 3450);
DOT 1 (2500 3500);
DOT 1 (2500 3550);
DOT 1 (2500 3600);
DOT 1 (2500 3650);
DOT 1 (2500 3700);
DOT 1 (-650 2850);
DOT 1 (-650 2750);
DOT 1 (-650 2250);
DOT 1 (-650 2200);
DOT 1 (-650 2150);
DOT 1 (-650 2000);
DOT 1 (-650 2050);
DOT 1 (-650 1950);
DOT 1 (-650 1900);
DOT 1 (-650 1850);
DOT 1 (-650 1750);
DOT 1 (-650 1800);
DOT 1 (-650 1700);
DOT 1 (-650 1650);
DOT 1 (-650 1600);
DOT 1 (-650 1500);
DOT 1 (-650 1550);
DOT 1 (-650 1450);
DOT 1 (-650 1400);
DOT 1 (-650 1350);
DOT 1 (-650 1300);
DOT 1 (-650 1250);
DOT 1 (-650 2550);
DOT 1 (-650 1200);
DOT 1 (-650 2300);
DOT 1 (-3200 1650);
DOT 1 (1100 2550);
FORCENOTE
PVDDQ (SINGLE SIDE) CAP: 10UF X1, 22UF X50
(-3975 5025) 0;
DISPLAY LEFT (-3975 5025);
DISPLAY 1.021277 (-3975 5025);
PAINT PURPLE (-3975 5025);
FORCENOTE
PVTT CAP: 100UF X2, 47UF X1
(-3975 5075) 0;
DISPLAY LEFT (-3975 5075);
DISPLAY 1.021277 (-3975 5075);
PAINT PURPLE (-3975 5075);
FORCENOTE
PVPP CAP: 10UF X12
(-3975 5125) 0;
DISPLAY LEFT (-3975 5125);
DISPLAY 1.021277 (-3975 5125);
PAINT PURPLE (-3975 5125);
FORCENOTE
CAP BETWEEN DIMM
(-3975 5225) 0;
DISPLAY LEFT (-3975 5225);
DISPLAY 1.276596 (-3975 5225);
PAINT PURPLE (-3975 5225);
FORCENOTE
PVDDQ (DOUBLE SIDE) CAP: 100UF X8, 47UF X41
(-3975 4975) 0;
DISPLAY LEFT (-3975 4975);
DISPLAY 1.021277 (-3975 4975);
PAINT PURPLE (-3975 4975);
FORCENOTE
SMBUS ADDR: 0XA4
(-5317 737) 0;
DISPLAY LEFT (-5317 737);
DISPLAY 1.957447 (-5317 737);
PAINT PURPLE (-5317 737);
FORCENOTE
PLACE CAP NEAR DIMM CONNECTOR
(-5304 900) 0;
DISPLAY LEFT (-5304 900);
DISPLAY 1.595745 (-5304 900);
PAINT PURPLE (-5304 900);
QUIT
